FILE_TYPE = MACRO_DRAWING;
SET COLOR_WIRE YELLOW;
SET COLOR_PROP MONO;
SET COLOR_DOT WHITE;
SET COLOR_ARC YELLOW;
SET COLOR_BODY GREEN;
SET COLOR_NOTE MONO;
SET PROP_DISPLAY VALUE;
SET PAGE_NUMBER P155;
FORCEADD CAP_A..1
(-4100 1050);
FORCEPROP 1 LASTPIN (-4100 950) $PN 2
J 0
(-4090 930);
DISPLAY 0.787234 (-4090 930);
PAINT ORANGE (-4090 930);
DISPLAY INVISIBLE (-4090 930);
FORCEPROP 1 LASTPIN (-4100 1150) $PN 1
J 0
(-4090 1130);
DISPLAY 0.787234 (-4090 1130);
PAINT ORANGE (-4090 1130);
DISPLAY INVISIBLE (-4090 1130);
FORCEPROP 2 LAST CDS_LIB dev_discrete
J 0
(-4100 1050);
PAINT ORANGE (-4100 1050);
DISPLAY INVISIBLE (-4100 1050);
FORCEPROP 2 LAST CDS_LOCATION C9A1
J 0
(-4050 1150);
DISPLAY 0.617021 (-4050 1150);
PAINT AQUA (-4050 1150);
DISPLAY INVISIBLE (-4050 1150);
FORCEPROP 2 LAST ROOM BMC_DEBUG_HEADER
J 0
(-4050 1200);
DISPLAY 1.021277 (-4050 1200);
PAINT ORANGE (-4050 1200);
DISPLAY INVISIBLE (-4050 1200);
FORCEPROP 1 LAST PATH I127
J 0
(-4050 1200);
DISPLAY 0.978723 (-4050 1200);
PAINT WHITE (-4050 1200);
DISPLAY INVISIBLE (-4050 1200);
FORCEPROP 2 LAST $SEC 1
J 0
(-4050 1250);
DISPLAY 0.680851 (-4050 1250);
PAINT MONO (-4050 1250);
DISPLAY INVISIBLE (-4050 1250);
FORCEPROP 2 LAST CDS_SEC 1
J 0
(-4050 1250);
DISPLAY 1.021277 (-4050 1250);
PAINT ORANGE (-4050 1250);
DISPLAY INVISIBLE (-4050 1250);
FORCEPROP 2 LAST BOM_COST DEBUG
J 0
(-4050 1250);
DISPLAY 1.021277 (-4050 1250);
PAINT ORANGE (-4050 1250);
DISPLAY INVISIBLE (-4050 1250);
FORCEPROP 1 LAST PART_NUMBER A36096-030
J 0
(-4050 900);
DISPLAY 0.617021 (-4050 900);
PAINT BLUE (-4050 900);
FORCEPROP 1 LAST PACK_TYPE 0402V
J 0
(-4050 850);
DISPLAY 0.617021 (-4050 850);
PAINT SKYBLUE (-4050 850);
FORCEPROP 1 LAST VOLTAGE 16V
J 0
(-4050 1050);
DISPLAY 0.617021 (-4050 1050);
PAINT SKYBLUE (-4050 1050);
FORCEPROP 1 LAST VALUE 0.1UF
J 0
(-4050 1100);
DISPLAY 0.617021 (-4050 1100);
PAINT SKYBLUE (-4050 1100);
FORCEPROP 1 LAST LOCATION C9A1
J 0
(-4050 1150);
DISPLAY 0.617021 (-4050 1150);
PAINT AQUA (-4050 1150);
FORCEPROP 1 LAST MATERIAL X7R
J 0
(-4050 950);
DISPLAY 0.617021 (-4050 950);
PAINT SKYBLUE (-4050 950);
FORCEPROP 1 LAST TOLERANCE 10%
J 0
(-4050 1000);
DISPLAY 0.617021 (-4050 1000);
PAINT SKYBLUE (-4050 1000);
FORCEADD GND..1
(-4100 825);
FORCEPROP 3 LASTPIN (-4100 875) SIG_NAME GND\g
J 0
(-4090 885);
DISPLAY 0.659574 (-4090 885);
PAINT MONO (-4090 885);
DISPLAY INVISIBLE (-4090 885);
FORCEPROP 1 LAST VOLTAGE 0.0V
J 0
(-4145 782);
DISPLAY 0.340426 (-4145 782);
PAINT SKYBLUE (-4145 782);
DISPLAY INVISIBLE (-4145 782);
FORCEPROP 2 LAST CDS_LIB mstr_symbols
J 0
(-4100 825);
PAINT ORANGE (-4100 825);
DISPLAY INVISIBLE (-4100 825);
FORCEPROP 1 LAST BODY_TYPE PLUMBING
J 0
(-4145 782);
DISPLAY 0.340426 (-4145 782);
PAINT GREEN (-4145 782);
DISPLAY INVISIBLE (-4145 782);
FORCEPROP 1 LAST SIZE 1B
J 0
(-4025 775);
DISPLAY 0.872340 (-4025 775);
PAINT AQUA (-4025 775);
DISPLAY INVISIBLE (-4025 775);
FORCEPROP 1 LAST PATH I128
J 0
(-4025 825);
DISPLAY 0.872340 (-4025 825);
PAINT AQUA (-4025 825);
DISPLAY INVISIBLE (-4025 825);
FORCEPROP 1 LAST HDL_POWER GND
J 0
(-4100 975);
DISPLAY 0.872340 (-4100 975);
PAINT GREEN (-4100 975);
DISPLAY INVISIBLE (-4100 975);
FORCEADD FUSE..1
(-4275 2625);
FORCEPROP 2 LAST ROOM BMC_DEBUG_HEADER
J 0
(-4425 2775);
DISPLAY 1.021277 (-4425 2775);
PAINT ORANGE (-4425 2775);
DISPLAY INVISIBLE (-4425 2775);
FORCEPROP 2 LAST CDS_LOCATION F1L1
J 0
(-4425 2725);
DISPLAY 0.617021 (-4425 2725);
PAINT AQUA (-4425 2725);
DISPLAY INVISIBLE (-4425 2725);
FORCEPROP 2 LAST SEC 1
J 0
(-4425 2775);
PAINT MONO (-4425 2775);
DISPLAY INVISIBLE (-4425 2775);
FORCEPROP 2 LAST BOM_COST DEBUG
J 0
(-4425 2825);
DISPLAY 1.021277 (-4425 2825);
PAINT ORANGE (-4425 2825);
DISPLAY INVISIBLE (-4425 2825);
FORCEPROP 2 LAST SEC_TYPE SMT
J 0
(-4425 2775);
DISPLAY 1.021277 (-4425 2775);
PAINT ORANGE (-4425 2775);
DISPLAY INVISIBLE (-4425 2775);
FORCEPROP 1 LAST PACK_TYPE SMT
J 0
(-4425 2775);
DISPLAY 0.978723 (-4425 2775);
PAINT SKYBLUE (-4425 2775);
DISPLAY INVISIBLE (-4425 2775);
FORCEPROP 2 LAST CDS_LIB mstr_discrete
J 0
(-4275 2625);
PAINT MONO (-4275 2625);
DISPLAY INVISIBLE (-4275 2625);
FORCEPROP 1 LAST PATH I129
J 0
(-3975 2675);
DISPLAY 0.978723 (-3975 2675);
PAINT BLUE (-3975 2675);
DISPLAY INVISIBLE (-3975 2675);
FORCEPROP 1 LASTPIN (-4425 2625) $PN 1
J 0
(-4440 2635);
DISPLAY 0.617021 (-4440 2635);
PAINT ORANGE (-4440 2635);
FORCEPROP 1 LAST MATERIAL IC
J 0
(-4425 2675);
DISPLAY 0.617021 (-4425 2675);
PAINT SKYBLUE (-4425 2675);
FORCEPROP 1 LASTPIN (-4125 2625) $PN 2
J 0
(-4140 2635);
DISPLAY 0.617021 (-4140 2635);
PAINT ORANGE (-4140 2635);
FORCEPROP 1 LAST PART_NUMBER H45581-001
J 0
(-4275 2725);
DISPLAY 0.617021 (-4275 2725);
PAINT BLUE (-4275 2725);
FORCEPROP 1 LAST LOCATION F1L1
J 0
(-4425 2725);
DISPLAY 0.617021 (-4425 2725);
PAINT AQUA (-4425 2725);
FORCEADD RES..2
(-6050 2575);
FORCEPROP 2 LAST BOM_COST DEBUG
J 0
(-6000 2800);
DISPLAY 1.021277 (-6000 2800);
PAINT ORANGE (-6000 2800);
DISPLAY INVISIBLE (-6000 2800);
FORCEPROP 2 LAST SEC_TYPE 0402
J 0
(-6000 2800);
DISPLAY 1.021277 (-6000 2800);
PAINT ORANGE (-6000 2800);
DISPLAY INVISIBLE (-6000 2800);
FORCEPROP 2 LAST SEC 1
J 0
(-6000 2800);
DISPLAY 0.680851 (-6000 2800);
PAINT MONO (-6000 2800);
DISPLAY INVISIBLE (-6000 2800);
FORCEPROP 1 LAST PATH I130
J 0
(-6000 2750);
DISPLAY 0.978723 (-6000 2750);
PAINT WHITE (-6000 2750);
DISPLAY INVISIBLE (-6000 2750);
FORCEPROP 2 LAST ROOM BMC_DEBUG_HEADER
J 0
(-6000 2750);
DISPLAY 1.021277 (-6000 2750);
PAINT ORANGE (-6000 2750);
DISPLAY INVISIBLE (-6000 2750);
FORCEPROP 2 LAST CDS_LOCATION R1L9
J 0
(-6005 2700);
DISPLAY 0.617021 (-6005 2700);
PAINT AQUA (-6005 2700);
DISPLAY INVISIBLE (-6005 2700);
FORCEPROP 2 LAST CDS_LIB mstr_discrete
J 0
(-6050 2575);
PAINT ORANGE (-6050 2575);
DISPLAY INVISIBLE (-6050 2575);
FORCEPROP 1 LAST LOCATION R1L9
J 0
(-6005 2700);
DISPLAY 0.617021 (-6005 2700);
PAINT AQUA (-6005 2700);
FORCEPROP 1 LAST MATERIAL CHIP
J 0
(-6010 2500);
DISPLAY 0.617021 (-6010 2500);
PAINT SKYBLUE (-6010 2500);
FORCEPROP 1 LAST VALUE 100.0K
J 0
(-6005 2650);
DISPLAY 0.617021 (-6005 2650);
PAINT SKYBLUE (-6005 2650);
FORCEPROP 1 LAST WATTAGE 1/16W
J 0
(-6010 2550);
DISPLAY 0.617021 (-6010 2550);
PAINT SKYBLUE (-6010 2550);
FORCEPROP 1 LAST TOLERANCE 1%
J 0
(-6005 2600);
DISPLAY 0.617021 (-6005 2600);
PAINT SKYBLUE (-6005 2600);
FORCEPROP 1 LASTPIN (-6050 2675) $PN 1
J 0
(-6045 2637);
DISPLAY 0.617021 (-6045 2637);
PAINT ORANGE (-6045 2637);
FORCEPROP 1 LASTPIN (-6050 2475) $PN 2
J 0
(-6045 2485);
DISPLAY 0.617021 (-6045 2485);
PAINT ORANGE (-6045 2485);
FORCEPROP 1 LAST PACK_TYPE 0402
J 0
(-6010 2400);
DISPLAY 0.617021 (-6010 2400);
PAINT SKYBLUE (-6010 2400);
FORCEPROP 1 LAST PART_NUMBER G21796-010
J 0
(-6010 2450);
DISPLAY 0.617021 (-6010 2450);
PAINT BLUE (-6010 2450);
FORCEADD CONN14_H54902001..1
(-4450 1500);
FORCEPROP 1 LAST CDS_LMAN_SYM_OUTLINE -250,250,250,-250
J 0
(-4450 1500);
DISPLAY 0.468085 (-4450 1500);
PAINT GREEN (-4450 1500);
DISPLAY INVISIBLE (-4450 1500);
FORCEPROP 2 LAST CDS_LIB mstr_conn
J 0
(-4450 1500);
PAINT ORANGE (-4450 1500);
DISPLAY INVISIBLE (-4450 1500);
FORCEPROP 0 LAST ROOM BMC_DEBUG_HEADER
J 0
(-4700 1950);
DISPLAY 1.021277 (-4700 1950);
PAINT ORANGE (-4700 1950);
DISPLAY INVISIBLE (-4700 1950);
FORCEPROP 2 LAST CDS_LOCATION J9A2
J 0
(-4700 1850);
DISPLAY 0.617021 (-4700 1850);
PAINT AQUA (-4700 1850);
DISPLAY INVISIBLE (-4700 1850);
FORCEPROP 2 LAST CDS_SEC 1
J 0
(-4700 1900);
PAINT MONO (-4700 1900);
DISPLAY INVISIBLE (-4700 1900);
FORCEPROP 1 LAST PACK_TYPE PIP
J 0
(-4700 1900);
PAINT SKYBLUE (-4700 1900);
DISPLAY INVISIBLE (-4700 1900);
FORCEPROP 2 LAST $SEC 1
J 0
(-4700 1900);
PAINT MONO (-4700 1900);
DISPLAY INVISIBLE (-4700 1900);
FORCEPROP 1 LAST PATH I171
J 0
(-4400 1800);
PAINT GREEN (-4400 1800);
DISPLAY INVISIBLE (-4400 1800);
FORCEPROP 0 LAST BOM_COST DEBUG
J 0
(-4700 2050);
DISPLAY 1.021277 (-4700 2050);
PAINT ORANGE (-4700 2050);
DISPLAY INVISIBLE (-4700 2050);
FORCEPROP 1 LAST PART_NUMBER H54902-001
J 0
(-4700 1200);
DISPLAY 0.617021 (-4700 1200);
PAINT BLUE (-4700 1200);
FORCEPROP 2 LASTPIN (-4150 1300) $PN 14
J 0
(-4140 1310);
DISPLAY 0.617021 (-4140 1310);
PAINT MONO (-4140 1310);
FORCEPROP 2 LASTPIN (-4750 1350) $PN 11
J 2
(-4760 1360);
DISPLAY 0.617021 (-4760 1360);
PAINT MONO (-4760 1360);
FORCEPROP 2 LASTPIN (-4750 1300) $PN 13
J 2
(-4760 1310);
DISPLAY 0.617021 (-4760 1310);
PAINT MONO (-4760 1310);
FORCEPROP 2 LASTPIN (-4750 1400) $PN 9
J 2
(-4760 1410);
DISPLAY 0.617021 (-4760 1410);
PAINT MONO (-4760 1410);
FORCEPROP 2 LASTPIN (-4750 1450) $PN 7
J 2
(-4760 1460);
DISPLAY 0.617021 (-4760 1460);
PAINT MONO (-4760 1460);
FORCEPROP 2 LASTPIN (-4750 1500) $PN 5
J 2
(-4760 1510);
DISPLAY 0.617021 (-4760 1510);
PAINT MONO (-4760 1510);
FORCEPROP 2 LASTPIN (-4750 1550) $PN 3
J 2
(-4760 1560);
DISPLAY 0.617021 (-4760 1560);
PAINT MONO (-4760 1560);
FORCEPROP 2 LASTPIN (-4150 1350) $PN 12
J 0
(-4140 1360);
DISPLAY 0.617021 (-4140 1360);
PAINT MONO (-4140 1360);
FORCEPROP 2 LASTPIN (-4150 1450) $PN 8
J 0
(-4140 1460);
DISPLAY 0.617021 (-4140 1460);
PAINT MONO (-4140 1460);
FORCEPROP 2 LASTPIN (-4150 1400) $PN 10
J 0
(-4140 1410);
DISPLAY 0.617021 (-4140 1410);
PAINT MONO (-4140 1410);
FORCEPROP 2 LASTPIN (-4150 1500) $PN 6
J 0
(-4140 1510);
DISPLAY 0.617021 (-4140 1510);
PAINT MONO (-4140 1510);
FORCEPROP 2 LASTPIN (-4150 1600) $PN 2
J 0
(-4140 1610);
DISPLAY 0.617021 (-4140 1610);
PAINT MONO (-4140 1610);
FORCEPROP 2 LASTPIN (-4150 1550) $PN 4
J 0
(-4140 1560);
DISPLAY 0.617021 (-4140 1560);
PAINT MONO (-4140 1560);
FORCEPROP 2 LASTPIN (-4750 1600) $PN 1
J 2
(-4760 1610);
DISPLAY 0.617021 (-4760 1610);
PAINT MONO (-4760 1610);
FORCEPROP 1 LAST MATERIAL CONN
J 0
(-4700 1800);
DISPLAY 0.617021 (-4700 1800);
PAINT SKYBLUE (-4700 1800);
FORCEPROP 1 LAST LOCATION J9A2
J 0
(-4700 1850);
DISPLAY 0.617021 (-4700 1850);
PAINT AQUA (-4700 1850);
FORCEADD TTL1G07_A..1
(-2550 1400);
FORCEPROP 1 LAST PACK_TYPE SOP
J 0
(-2600 1650);
DISPLAY 0.978723 (-2600 1650);
PAINT SKYBLUE (-2600 1650);
DISPLAY INVISIBLE (-2600 1650);
FORCEPROP 0 LAST BOM_COST DEBUG
J 0
(-2600 1800);
DISPLAY 1.021277 (-2600 1800);
PAINT ORANGE (-2600 1800);
DISPLAY INVISIBLE (-2600 1800);
FORCEPROP 2 LAST SEC_TYPE SOP
J 0
(-2600 1650);
DISPLAY 1.021277 (-2600 1650);
PAINT ORANGE (-2600 1650);
DISPLAY INVISIBLE (-2600 1650);
FORCEPROP 2 LAST SEC 1
J 0
(-2600 1650);
DISPLAY 0.680851 (-2600 1650);
PAINT MONO (-2600 1650);
DISPLAY INVISIBLE (-2600 1650);
FORCEPROP 2 LAST CDS_LOCATION U9A1
J 0
(-2600 1600);
DISPLAY 0.617021 (-2600 1600);
PAINT AQUA (-2600 1600);
DISPLAY INVISIBLE (-2600 1600);
FORCEPROP 0 LAST ROOM BMC_DEBUG_HEADER
J 0
(-2600 1700);
DISPLAY 1.021277 (-2600 1700);
PAINT ORANGE (-2600 1700);
DISPLAY INVISIBLE (-2600 1700);
FORCEPROP 2 LAST CDS_LIB mstr_ttl
J 0
(-2550 1400);
PAINT ORANGE (-2550 1400);
DISPLAY INVISIBLE (-2550 1400);
FORCEPROP 1 LAST PATH I178
J 0
(-2500 1450);
DISPLAY 0.978723 (-2500 1450);
PAINT WHITE (-2500 1450);
DISPLAY INVISIBLE (-2500 1450);
FORCEPROP 1 LAST PART_NUMBER C88419-001
J 0
(-2600 1265);
DISPLAY 0.617021 (-2600 1265);
PAINT BLUE (-2600 1265);
FORCEPROP 2 LASTPIN (-2400 1400) $PN 4
J 0
(-2390 1410);
DISPLAY 0.617021 (-2390 1410);
PAINT ORANGE (-2390 1410);
FORCEPROP 1 LAST VALUE 74LVC1G07
J 1
(-2550 1500);
DISPLAY 0.617021 (-2550 1500);
PAINT SKYBLUE (-2550 1500);
FORCEPROP 2 LASTPIN (-2650 1400) $PN 2
J 2
(-2660 1410);
DISPLAY 0.617021 (-2660 1410);
PAINT ORANGE (-2660 1410);
FORCEPROP 1 LAST MATERIAL IC
J 0
(-2600 1550);
DISPLAY 0.617021 (-2600 1550);
PAINT SKYBLUE (-2600 1550);
FORCEPROP 1 LAST LOCATION U9A1
J 0
(-2600 1600);
DISPLAY 0.617021 (-2600 1600);
PAINT AQUA (-2600 1600);
FORCEPROP 1 LAST POWER_GROUP VCC=P3V3_STBY;GND=GND
J 1
(-2600 1210);
DISPLAY 0.617021 (-2600 1210);
PAINT ORANGE (-2600 1210);
FORCEADD GND..1
(-6050 1600);
FORCEPROP 3 LASTPIN (-6050 1650) SIG_NAME GND\g
J 0
(-6040 1660);
DISPLAY 0.659574 (-6040 1660);
PAINT MONO (-6040 1660);
DISPLAY INVISIBLE (-6040 1660);
FORCEPROP 1 LAST BODY_TYPE PLUMBING
J 0
(-6095 1557);
DISPLAY 0.340426 (-6095 1557);
PAINT GREEN (-6095 1557);
DISPLAY INVISIBLE (-6095 1557);
FORCEPROP 1 LAST VOLTAGE 0.0V
J 0
(-6095 1557);
DISPLAY 0.340426 (-6095 1557);
PAINT SKYBLUE (-6095 1557);
DISPLAY INVISIBLE (-6095 1557);
FORCEPROP 1 LAST SIZE 1B
J 0
(-5975 1550);
DISPLAY 0.872340 (-5975 1550);
PAINT AQUA (-5975 1550);
DISPLAY INVISIBLE (-5975 1550);
FORCEPROP 2 LAST CDS_LIB mstr_symbols
J 0
(-6050 1600);
PAINT ORANGE (-6050 1600);
DISPLAY INVISIBLE (-6050 1600);
FORCEPROP 1 LAST HDL_POWER GND
J 0
(-6050 1750);
DISPLAY 0.872340 (-6050 1750);
PAINT GREEN (-6050 1750);
DISPLAY INVISIBLE (-6050 1750);
FORCEPROP 1 LAST PATH I180
J 0
(-5975 1600);
DISPLAY 0.872340 (-5975 1600);
PAINT AQUA (-5975 1600);
DISPLAY INVISIBLE (-5975 1600);
FORCEADD OFFPAGE..1
(-7700 2000);
FORCEPROP 1 LAST COMMENT_BODY TRUE
J 0
(-7575 1900);
DISPLAY 0.872340 (-7575 1900);
PAINT GREEN (-7575 1900);
DISPLAY INVISIBLE (-7575 1900);
FORCEPROP 1 LAST OFFPAGE TRUE
J 0
(-7375 1875);
DISPLAY 0.872340 (-7375 1875);
PAINT GREEN (-7375 1875);
DISPLAY INVISIBLE (-7375 1875);
FORCEPROP 2 LAST CDS_LIB mstr_standard
J 0
(-7700 2000);
PAINT ORANGE (-7700 2000);
DISPLAY INVISIBLE (-7700 2000);
FORCEPROP 2 LAST PATH I182
J 0
(-7650 2075);
DISPLAY 1.021277 (-7650 2075);
PAINT ORANGE (-7650 2075);
DISPLAY INVISIBLE (-7650 2075);
FORCEPROP 2 LAST $XR0 190 
J 0
(-7952 2000);
DISPLAY 0.638298 (-7952 2000);
PAINT MONO (-7952 2000);
FORCEADD P3V3_STBY..1
(-1550 3325);
FORCEPROP 3 LASTPIN (-1550 3275) SIG_NAME P3V3_STBY\g
J 0
(-1540 3285);
DISPLAY 0.659574 (-1540 3285);
PAINT MONO (-1540 3285);
DISPLAY INVISIBLE (-1540 3285);
FORCEPROP 1 LAST HDL_POWER P3V3_STBY
J 0
(-1850 3200);
DISPLAY 0.872340 (-1850 3200);
PAINT ORANGE (-1850 3200);
DISPLAY INVISIBLE (-1850 3200);
FORCEPROP 1 LAST VOLTAGE 3.3V
J 0
(-1595 3282);
DISPLAY 0.340426 (-1595 3282);
PAINT SKYBLUE (-1595 3282);
DISPLAY INVISIBLE (-1595 3282);
FORCEPROP 1 LAST BODY_TYPE PLUMBING
J 0
(-1595 3282);
DISPLAY 0.340426 (-1595 3282);
PAINT GREEN (-1595 3282);
DISPLAY INVISIBLE (-1595 3282);
FORCEPROP 2 LAST CDS_LIB mstr_symbols
J 0
(-1550 3325);
PAINT ORANGE (-1550 3325);
DISPLAY INVISIBLE (-1550 3325);
FORCEPROP 1 LAST SIZE 1B
J 0
(-1505 3347);
DISPLAY 0.340426 (-1505 3347);
PAINT GREEN (-1505 3347);
DISPLAY INVISIBLE (-1505 3347);
FORCEPROP 1 LAST PATH I183
J 0
(-1505 3327);
DISPLAY 0.340426 (-1505 3327);
PAINT GREEN (-1505 3327);
DISPLAY INVISIBLE (-1505 3327);
FORCEADD CAP_A..1
(-1550 3025);
FORCEPROP 2 LAST CDS_LIB dev_discrete
J 0
(-1550 3025);
PAINT ORANGE (-1550 3025);
DISPLAY INVISIBLE (-1550 3025);
FORCEPROP 2 LAST CDS_LOCATION C1T56
J 0
(-1500 3125);
DISPLAY 0.617021 (-1500 3125);
PAINT AQUA (-1500 3125);
DISPLAY INVISIBLE (-1500 3125);
FORCEPROP 2 LAST SEC 1
J 0
(-1500 3175);
DISPLAY 0.680851 (-1500 3175);
PAINT MONO (-1500 3175);
DISPLAY INVISIBLE (-1500 3175);
FORCEPROP 2 LAST CDS_SEC 1
J 0
(-1500 3175);
PAINT ORANGE (-1500 3175);
DISPLAY INVISIBLE (-1500 3175);
FORCEPROP 2 LAST ROOM BMC_DEBUG_HEADER
J 0
(-1500 3175);
DISPLAY 1.021277 (-1500 3175);
PAINT ORANGE (-1500 3175);
DISPLAY INVISIBLE (-1500 3175);
FORCEPROP 1 LAST PATH I184
J 0
(-1500 3175);
DISPLAY 0.978723 (-1500 3175);
PAINT WHITE (-1500 3175);
DISPLAY INVISIBLE (-1500 3175);
FORCEPROP 2 LAST SEC_TYPE 0402V
J 0
(-1500 3225);
DISPLAY 1.021277 (-1500 3225);
PAINT ORANGE (-1500 3225);
DISPLAY INVISIBLE (-1500 3225);
FORCEPROP 2 LAST BOM_COST DEBUG
J 0
(-1500 3225);
DISPLAY 1.021277 (-1500 3225);
PAINT ORANGE (-1500 3225);
DISPLAY INVISIBLE (-1500 3225);
FORCEPROP 1 LASTPIN (-1550 2925) $PN 2
J 0
(-1540 2905);
DISPLAY 0.617021 (-1540 2905);
PAINT ORANGE (-1540 2905);
FORCEPROP 1 LAST VOLTAGE 16V
J 0
(-1500 3025);
DISPLAY 0.617021 (-1500 3025);
PAINT SKYBLUE (-1500 3025);
FORCEPROP 1 LAST TOLERANCE 10%
J 0
(-1500 2975);
DISPLAY 0.617021 (-1500 2975);
PAINT SKYBLUE (-1500 2975);
FORCEPROP 1 LAST MATERIAL X7R
J 0
(-1500 2925);
DISPLAY 0.617021 (-1500 2925);
PAINT SKYBLUE (-1500 2925);
FORCEPROP 1 LAST PACK_TYPE 0402V
J 0
(-1500 2825);
DISPLAY 0.617021 (-1500 2825);
PAINT SKYBLUE (-1500 2825);
FORCEPROP 1 LASTPIN (-1550 3125) $PN 1
J 0
(-1540 3105);
DISPLAY 0.617021 (-1540 3105);
PAINT ORANGE (-1540 3105);
FORCEPROP 1 LAST VALUE 0.1UF
J 0
(-1500 3075);
DISPLAY 0.617021 (-1500 3075);
PAINT SKYBLUE (-1500 3075);
FORCEPROP 1 LAST LOCATION C1T56
J 0
(-1500 3125);
DISPLAY 0.617021 (-1500 3125);
PAINT AQUA (-1500 3125);
FORCEPROP 1 LAST PART_NUMBER A36096-030
J 0
(-1500 2875);
DISPLAY 0.617021 (-1500 2875);
PAINT BLUE (-1500 2875);
FORCEADD GND..1
(-1550 2725);
FORCEPROP 3 LASTPIN (-1550 2775) SIG_NAME GND\g
J 0
(-1540 2785);
DISPLAY 0.659574 (-1540 2785);
PAINT MONO (-1540 2785);
DISPLAY INVISIBLE (-1540 2785);
FORCEPROP 1 LAST VOLTAGE 0.0V
J 0
(-1595 2682);
DISPLAY 0.340426 (-1595 2682);
PAINT SKYBLUE (-1595 2682);
DISPLAY INVISIBLE (-1595 2682);
FORCEPROP 2 LAST CDS_LIB mstr_symbols
J 0
(-1550 2725);
PAINT ORANGE (-1550 2725);
DISPLAY INVISIBLE (-1550 2725);
FORCEPROP 1 LAST BODY_TYPE PLUMBING
J 0
(-1595 2682);
DISPLAY 0.340426 (-1595 2682);
PAINT GREEN (-1595 2682);
DISPLAY INVISIBLE (-1595 2682);
FORCEPROP 1 LAST HDL_POWER GND
J 0
(-1550 2875);
DISPLAY 0.872340 (-1550 2875);
PAINT GREEN (-1550 2875);
DISPLAY INVISIBLE (-1550 2875);
FORCEPROP 1 LAST SIZE 1B
J 0
(-1475 2675);
DISPLAY 0.872340 (-1475 2675);
PAINT AQUA (-1475 2675);
DISPLAY INVISIBLE (-1475 2675);
FORCEPROP 1 LAST PATH I185
J 0
(-1475 2725);
DISPLAY 0.872340 (-1475 2725);
PAINT AQUA (-1475 2725);
DISPLAY INVISIBLE (-1475 2725);
FORCEADD RES..1
(-7050 2000);
FORCEPROP 2 LAST $SEC 1
J 0
(-7100 2200);
PAINT MONO (-7100 2200);
DISPLAY INVISIBLE (-7100 2200);
FORCEPROP 2 LAST CDS_LOCATION R1L2
J 0
(-7100 2050);
DISPLAY 0.617021 (-7100 2050);
PAINT AQUA (-7100 2050);
DISPLAY INVISIBLE (-7100 2050);
FORCEPROP 1 LAST PATH I186
J 0
(-7100 2150);
DISPLAY 0.978723 (-7100 2150);
PAINT WHITE (-7100 2150);
DISPLAY INVISIBLE (-7100 2150);
FORCEPROP 2 LAST ROOM BMC_DEBUG_HEADER
J 0
(-7100 2100);
DISPLAY 1.021277 (-7100 2100);
PAINT ORANGE (-7100 2100);
DISPLAY INVISIBLE (-7100 2100);
FORCEPROP 2 LAST CDS_SEC 1
J 0
(-7100 2200);
PAINT MONO (-7100 2200);
DISPLAY INVISIBLE (-7100 2200);
FORCEPROP 2 LAST BOM_COST DEBUG
J 0
(-7100 2150);
DISPLAY 1.021277 (-7100 2150);
PAINT ORANGE (-7100 2150);
DISPLAY INVISIBLE (-7100 2150);
FORCEPROP 2 LAST CDS_LIB mstr_discrete
J 0
(-7050 2000);
PAINT ORANGE (-7050 2000);
DISPLAY INVISIBLE (-7050 2000);
FORCEPROP 1 LAST MATERIAL CHIP
J 0
(-7050 1850);
DISPLAY 0.978723 (-7050 1850);
PAINT SKYBLUE (-7050 1850);
DISPLAY INVISIBLE (-7050 1850);
FORCEPROP 1 LAST PART_NUMBER G21796-066
J 0
(-7150 1900);
DISPLAY 0.617021 (-7150 1900);
PAINT BLUE (-7150 1900);
FORCEPROP 1 LAST WATTAGE 1/16W
J 2
(-7175 1950);
DISPLAY 0.617021 (-7175 1950);
PAINT SKYBLUE (-7175 1950);
FORCEPROP 1 LAST PACK_TYPE 0402
J 0
(-6900 1950);
DISPLAY 0.617021 (-6900 1950);
PAINT SKYBLUE (-6900 1950);
FORCEPROP 1 LAST TOLERANCE 1%
J 0
(-7000 1950);
DISPLAY 0.617021 (-7000 1950);
PAINT SKYBLUE (-7000 1950);
FORCEPROP 1 LAST LOCATION R1L2
J 0
(-7100 2050);
DISPLAY 0.617021 (-7100 2050);
PAINT AQUA (-7100 2050);
FORCEPROP 1 LASTPIN (-7150 2000) $PN 1
J 0
(-7138 2012);
DISPLAY 0.617021 (-7138 2012);
PAINT ORANGE (-7138 2012);
FORCEPROP 1 LASTPIN (-6950 2000) $PN 2
J 0
(-6988 2012);
DISPLAY 0.617021 (-6988 2012);
PAINT ORANGE (-6988 2012);
FORCEPROP 1 LAST VALUE 10.0
J 2
(-7075 1950);
DISPLAY 0.617021 (-7075 1950);
PAINT SKYBLUE (-7075 1950);
FORCEADD FET_N_DUAL..5
(-6050 2100);
FORCEPROP 1 LAST PACK_TYPE SMLF
J 0
(-5850 1950);
DISPLAY 0.978723 (-5850 1950);
PAINT SKYBLUE (-5850 1950);
DISPLAY INVISIBLE (-5850 1950);
FORCEPROP 2 LAST CDS_LIB mstr_discrete
J 0
(-6050 2100);
PAINT ORANGE (-6050 2100);
DISPLAY INVISIBLE (-6050 2100);
FORCEPROP 0 LAST ROOM BMC
J 0
(-5850 2200);
DISPLAY 1.021277 (-5850 2200);
PAINT ORANGE (-5850 2200);
DISPLAY INVISIBLE (-5850 2200);
FORCEPROP 1 LAST PATH I187
J 0
(-5850 2150);
DISPLAY 0.978723 (-5850 2150);
PAINT BLUE (-5850 2150);
DISPLAY INVISIBLE (-5850 2150);
FORCEPROP 2 LAST CDS_LOCATION Q1L2
J 0
(-5850 2100);
DISPLAY 0.617021 (-5850 2100);
PAINT AQUA (-5850 2100);
DISPLAY INVISIBLE (-5850 2100);
FORCEPROP 2 LAST SEC 2
J 0
(-5850 2200);
DISPLAY 0.680851 (-5850 2200);
PAINT MONO (-5850 2200);
DISPLAY INVISIBLE (-5850 2200);
FORCEPROP 0 LAST BOM_COST BMC_DEBUG_HEADER
J 0
(-5850 2300);
DISPLAY 1.021277 (-5850 2300);
PAINT ORANGE (-5850 2300);
DISPLAY INVISIBLE (-5850 2300);
FORCEPROP 2 LAST SEC_TYPE SMLF
J 0
(-5850 2200);
DISPLAY 1.021277 (-5850 2200);
PAINT ORANGE (-5850 2200);
DISPLAY INVISIBLE (-5850 2200);
FORCEPROP 1 LAST PART_NUMBER E40049-001
J 0
(-5850 1900);
DISPLAY 0.617021 (-5850 1900);
PAINT BLUE (-5850 1900);
FORCEPROP 1 LAST MATERIAL FET
J 0
(-5850 2000);
DISPLAY 0.617021 (-5850 2000);
PAINT SKYBLUE (-5850 2000);
FORCEPROP 1 LASTPIN (-6250 2000) $PN 5
J 2
(-6247 2015);
DISPLAY 0.617021 (-6247 2015);
PAINT WHITE (-6247 2015);
FORCEPROP 1 LASTPIN (-6050 1900) $PN 4
J 2
(-5992 1900);
DISPLAY 0.617021 (-5992 1900);
PAINT WHITE (-5992 1900);
FORCEPROP 1 LASTPIN (-6050 2300) $PN 3
J 2
(-5997 2265);
DISPLAY 0.617021 (-5997 2265);
PAINT WHITE (-5997 2265);
FORCEPROP 1 LAST LOCATION Q1L2
J 0
(-5850 2100);
DISPLAY 0.617021 (-5850 2100);
PAINT AQUA (-5850 2100);
FORCEPROP 1 LAST VALUE NTJD4001N
J 0
(-5850 2050);
DISPLAY 0.617021 (-5850 2050);
PAINT SKYBLUE (-5850 2050);
FORCEADD FET_N_DUAL..5
R 1
(-4950 2625);
FORCEPROP 2 LAST CDS_LOCATION Q1L2
J 0
(-4725 2475);
DISPLAY 0.617021 (-4725 2475);
PAINT AQUA (-4725 2475);
DISPLAY INVISIBLE (-4725 2475);
FORCEPROP 2 LAST SEC 1
R 1
J 0
(-5050 2825);
DISPLAY 0.680851 (-5050 2825);
PAINT MONO (-5050 2825);
DISPLAY INVISIBLE (-5050 2825);
FORCEPROP 2 LAST SEC_TYPE SMLF
R 1
J 0
(-5050 2825);
DISPLAY 1.021277 (-5050 2825);
PAINT ORANGE (-5050 2825);
DISPLAY INVISIBLE (-5050 2825);
FORCEPROP 2 LAST CDS_LIB mstr_discrete
R 1
J 0
(-4950 2625);
PAINT ORANGE (-4950 2625);
DISPLAY INVISIBLE (-4950 2625);
FORCEPROP 1 LAST PATH I188
R 1
J 0
(-5000 2825);
DISPLAY 0.978723 (-5000 2825);
PAINT BLUE (-5000 2825);
DISPLAY INVISIBLE (-5000 2825);
FORCEPROP 1 LAST PACK_TYPE SMLF
R 1
J 0
(-4800 2825);
DISPLAY 0.978723 (-4800 2825);
PAINT SKYBLUE (-4800 2825);
DISPLAY INVISIBLE (-4800 2825);
FORCEPROP 0 LAST ROOM BMC
R 1
J 0
(-4725 2575);
DISPLAY 1.021277 (-4725 2575);
PAINT ORANGE (-4725 2575);
DISPLAY INVISIBLE (-4725 2575);
FORCEPROP 0 LAST BOM_COST BMC_DEBUG_HEADER
R 1
J 0
(-4750 2625);
DISPLAY 1.021277 (-4750 2625);
PAINT ORANGE (-4750 2625);
DISPLAY INVISIBLE (-4750 2625);
FORCEPROP 1 LAST LOCATION Q1L2
J 0
(-4725 2475);
DISPLAY 0.617021 (-4725 2475);
PAINT AQUA (-4725 2475);
FORCEPROP 1 LAST PART_NUMBER E40049-001
J 0
(-4725 2300);
DISPLAY 0.617021 (-4725 2300);
PAINT BLUE (-4725 2300);
FORCEPROP 1 LAST VALUE NTJD4001N
J 0
(-4725 2425);
DISPLAY 0.617021 (-4725 2425);
PAINT SKYBLUE (-4725 2425);
FORCEPROP 1 LAST MATERIAL FET
J 0
(-4725 2375);
DISPLAY 0.617021 (-4725 2375);
PAINT SKYBLUE (-4725 2375);
FORCEPROP 1 LASTPIN (-4850 2425) $PN 2
R 1
J 2
(-4865 2428);
DISPLAY 0.617021 (-4865 2428);
PAINT WHITE (-4865 2428);
FORCEPROP 1 LASTPIN (-5150 2625) $PN 6
R 1
J 2
(-5115 2678);
DISPLAY 0.617021 (-5115 2678);
PAINT WHITE (-5115 2678);
FORCEPROP 1 LASTPIN (-4750 2625) $PN 1
R 1
J 2
(-4750 2683);
DISPLAY 0.617021 (-4750 2683);
PAINT WHITE (-4750 2683);
FORCEADD RES..2
(-2950 1725);
FORCEPROP 2 LAST CDS_LIB mstr_discrete
J 0
(-2950 1725);
PAINT ORANGE (-2950 1725);
DISPLAY INVISIBLE (-2950 1725);
FORCEPROP 2 LAST CDS_LOCATION R9A6
J 0
(-2905 1850);
DISPLAY 0.617021 (-2905 1850);
PAINT AQUA (-2905 1850);
DISPLAY INVISIBLE (-2905 1850);
FORCEPROP 1 LAST PATH I191
J 0
(-2900 1900);
DISPLAY 0.978723 (-2900 1900);
PAINT WHITE (-2900 1900);
DISPLAY INVISIBLE (-2900 1900);
FORCEPROP 0 LAST ROOM BMC
J 0
(-2900 1950);
DISPLAY 1.021277 (-2900 1950);
PAINT ORANGE (-2900 1950);
DISPLAY INVISIBLE (-2900 1950);
FORCEPROP 2 LAST $SEC 1
J 0
(-2900 1950);
PAINT MONO (-2900 1950);
DISPLAY INVISIBLE (-2900 1950);
FORCEPROP 2 LAST CDS_SEC 1
J 0
(-2900 1950);
PAINT MONO (-2900 1950);
DISPLAY INVISIBLE (-2900 1950);
FORCEPROP 0 LAST BOM_COST BMC_DEBUG_HEADER
J 0
(-2900 2050);
DISPLAY 1.021277 (-2900 2050);
PAINT ORANGE (-2900 2050);
DISPLAY INVISIBLE (-2900 2050);
FORCEPROP 1 LAST MATERIAL EMPTY
J 0
(-2910 1650);
DISPLAY 0.617021 (-2910 1650);
PAINT RED (-2910 1650);
FORCEPROP 1 LAST WATTAGE 1/16W
J 0
(-2910 1700);
DISPLAY 0.617021 (-2910 1700);
PAINT SKYBLUE (-2910 1700);
FORCEPROP 1 LAST VALUE 20.0K
J 0
(-2905 1800);
DISPLAY 0.617021 (-2905 1800);
PAINT SKYBLUE (-2905 1800);
FORCEPROP 1 LAST LOCATION R9A6
J 0
(-2905 1850);
DISPLAY 0.617021 (-2905 1850);
PAINT AQUA (-2905 1850);
FORCEPROP 1 LASTPIN (-2950 1825) $PN 1
J 0
(-2945 1787);
DISPLAY 0.617021 (-2945 1787);
PAINT ORANGE (-2945 1787);
FORCEPROP 1 LASTPIN (-2950 1625) $PN 2
J 0
(-2945 1635);
DISPLAY 0.617021 (-2945 1635);
PAINT ORANGE (-2945 1635);
FORCEPROP 1 LAST TOLERANCE 1%
J 0
(-2905 1750);
DISPLAY 0.617021 (-2905 1750);
PAINT SKYBLUE (-2905 1750);
FORCEPROP 1 LAST PACK_TYPE 0402
J 0
(-2910 1550);
DISPLAY 0.617021 (-2910 1550);
PAINT SKYBLUE (-2910 1550);
FORCEPROP 1 LAST PART_NUMBER G21796-040
J 0
(-2910 1600);
DISPLAY 0.617021 (-2910 1600);
PAINT BLUE (-2910 1600);
FORCEADD P5V_STBY..1
(-2950 1975);
FORCEPROP 3 LASTPIN (-2950 1925) SIG_NAME P5V_STBY\g
J 0
(-2940 1935);
DISPLAY 0.659574 (-2940 1935);
PAINT MONO (-2940 1935);
DISPLAY INVISIBLE (-2940 1935);
FORCEPROP 1 LAST HDL_POWER P5V_STBY
J 0
(-3250 1850);
DISPLAY 0.872340 (-3250 1850);
PAINT ORANGE (-3250 1850);
DISPLAY INVISIBLE (-3250 1850);
FORCEPROP 1 LAST PATH I192
J 0
(-2905 1977);
DISPLAY 0.340426 (-2905 1977);
PAINT GREEN (-2905 1977);
DISPLAY INVISIBLE (-2905 1977);
FORCEPROP 1 LAST BODY_TYPE PLUMBING
J 0
(-2995 1932);
DISPLAY 0.340426 (-2995 1932);
PAINT GREEN (-2995 1932);
DISPLAY INVISIBLE (-2995 1932);
FORCEPROP 2 LAST CDS_LIB mstr_symbols
J 0
(-2950 1975);
PAINT ORANGE (-2950 1975);
DISPLAY INVISIBLE (-2950 1975);
FORCEPROP 1 LAST SIZE 1B
J 0
(-2905 1997);
DISPLAY 0.340426 (-2905 1997);
PAINT GREEN (-2905 1997);
DISPLAY INVISIBLE (-2905 1997);
FORCEPROP 1 LAST VOLTAGE 5.0V
J 0
(-2995 1932);
DISPLAY 0.340426 (-2995 1932);
PAINT SKYBLUE (-2995 1932);
DISPLAY INVISIBLE (-2995 1932);
FORCEADD P12V_STBY..1
(-6050 2900);
FORCEPROP 3 LASTPIN (-6050 2850) SIG_NAME P12V_STBY\g
J 0
(-6040 2860);
DISPLAY 0.659574 (-6040 2860);
PAINT MONO (-6040 2860);
DISPLAY INVISIBLE (-6040 2860);
FORCEPROP 2 LAST CDS_LIB mstr_symbols
J 0
(-6050 2900);
PAINT ORANGE (-6050 2900);
DISPLAY INVISIBLE (-6050 2900);
FORCEPROP 1 LAST PATH I193
J 0
(-6005 2902);
DISPLAY 0.340426 (-6005 2902);
PAINT GREEN (-6005 2902);
DISPLAY INVISIBLE (-6005 2902);
FORCEPROP 1 LAST HDL_POWER P12V_STBY
J 0
(-6350 2775);
DISPLAY 0.872340 (-6350 2775);
PAINT ORANGE (-6350 2775);
DISPLAY INVISIBLE (-6350 2775);
FORCEPROP 1 LAST BODY_TYPE PLUMBING
J 0
(-6095 2857);
DISPLAY 0.340426 (-6095 2857);
PAINT GREEN (-6095 2857);
DISPLAY INVISIBLE (-6095 2857);
FORCEPROP 1 LAST SIZE 1B
J 0
(-6005 2922);
DISPLAY 0.340426 (-6005 2922);
PAINT GREEN (-6005 2922);
DISPLAY INVISIBLE (-6005 2922);
FORCEPROP 1 LAST VOLTAGE 12.0V
J 0
(-6095 2857);
DISPLAY 0.340426 (-6095 2857);
PAINT SKYBLUE (-6095 2857);
DISPLAY INVISIBLE (-6095 2857);
FORCEADD P5V_STBY..1
(-3325 1975);
FORCEPROP 3 LASTPIN (-3325 1925) SIG_NAME P5V_STBY\g
J 0
(-3315 1935);
DISPLAY 0.659574 (-3315 1935);
PAINT MONO (-3315 1935);
DISPLAY INVISIBLE (-3315 1935);
FORCEPROP 1 LAST HDL_POWER P5V_STBY
J 0
(-3625 1850);
DISPLAY 0.872340 (-3625 1850);
PAINT ORANGE (-3625 1850);
DISPLAY INVISIBLE (-3625 1850);
FORCEPROP 1 LAST PATH I194
J 0
(-3280 1977);
DISPLAY 0.340426 (-3280 1977);
PAINT GREEN (-3280 1977);
DISPLAY INVISIBLE (-3280 1977);
FORCEPROP 1 LAST BODY_TYPE PLUMBING
J 0
(-3370 1932);
DISPLAY 0.340426 (-3370 1932);
PAINT GREEN (-3370 1932);
DISPLAY INVISIBLE (-3370 1932);
FORCEPROP 1 LAST SIZE 1B
J 0
(-3280 1997);
DISPLAY 0.340426 (-3280 1997);
PAINT GREEN (-3280 1997);
DISPLAY INVISIBLE (-3280 1997);
FORCEPROP 2 LAST CDS_LIB mstr_symbols
J 0
(-3325 1975);
PAINT ORANGE (-3325 1975);
DISPLAY INVISIBLE (-3325 1975);
FORCEPROP 1 LAST VOLTAGE 5.0V
J 0
(-3370 1932);
DISPLAY 0.340426 (-3370 1932);
PAINT SKYBLUE (-3370 1932);
DISPLAY INVISIBLE (-3370 1932);
FORCEADD RES..2
R 2
(-3325 1725);
FORCEPROP 1 LASTPIN (-3325 1825) $PN 1
J 2
(-3330 1787);
DISPLAY 0.787234 (-3330 1787);
PAINT ORANGE (-3330 1787);
DISPLAY INVISIBLE (-3330 1787);
FORCEPROP 1 LASTPIN (-3325 1625) $PN 2
J 2
(-3330 1635);
DISPLAY 0.787234 (-3330 1635);
PAINT ORANGE (-3330 1635);
DISPLAY INVISIBLE (-3330 1635);
FORCEPROP 0 LAST ROOM IO_SLOT
J 2
(-3375 1950);
DISPLAY 1.021277 (-3375 1950);
PAINT ORANGE (-3375 1950);
DISPLAY INVISIBLE (-3375 1950);
FORCEPROP 0 LAST BOM_COST IO_SLOT
J 2
(-3375 2050);
DISPLAY 1.021277 (-3375 2050);
PAINT ORANGE (-3375 2050);
DISPLAY INVISIBLE (-3375 2050);
FORCEPROP 1 LAST PATH I195
J 2
(-3375 1900);
DISPLAY 0.978723 (-3375 1900);
PAINT WHITE (-3375 1900);
DISPLAY INVISIBLE (-3375 1900);
FORCEPROP 2 LAST CDS_LIB mstr_discrete
J 0
(-3325 1725);
PAINT MONO (-3325 1725);
DISPLAY INVISIBLE (-3325 1725);
FORCEPROP 1 LAST PART_NUMBER G21796-107
J 2
(-3015 1850);
DISPLAY 0.617021 (-3015 1850);
PAINT BLUE (-3015 1850);
FORCEPROP 1 LAST MATERIAL CHIP
J 2
(-3365 1650);
DISPLAY 0.617021 (-3365 1650);
PAINT SKYBLUE (-3365 1650);
FORCEPROP 1 LAST WATTAGE 1/16W
J 2
(-3365 1700);
DISPLAY 0.617021 (-3365 1700);
PAINT SKYBLUE (-3365 1700);
FORCEPROP 1 LAST PACK_TYPE 0402
J 2
(-3490 1650);
DISPLAY 0.617021 (-3490 1650);
PAINT SKYBLUE (-3490 1650);
FORCEPROP 1 LAST TOLERANCE 1%
J 2
(-3370 1750);
DISPLAY 0.617021 (-3370 1750);
PAINT SKYBLUE (-3370 1750);
FORCEPROP 1 LAST VALUE 15.0K
J 2
(-3370 1800);
DISPLAY 0.617021 (-3370 1800);
PAINT SKYBLUE (-3370 1800);
FORCEPROP 1 LAST LOCATION R9A5
J 2
(-3370 1850);
DISPLAY 0.617021 (-3370 1850);
PAINT AQUA (-3370 1850);
FORCEADD RES..1
(-2400 1775);
FORCEPROP 1 LASTPIN (-2300 1775) $PN 2
J 0
(-2338 1787);
DISPLAY 0.787234 (-2338 1787);
PAINT ORANGE (-2338 1787);
DISPLAY INVISIBLE (-2338 1787);
FORCEPROP 1 LASTPIN (-2500 1775) $PN 1
J 0
(-2488 1787);
DISPLAY 0.787234 (-2488 1787);
PAINT ORANGE (-2488 1787);
DISPLAY INVISIBLE (-2488 1787);
FORCEPROP 2 LAST BOM_COST DEBUG
J 0
(-2450 1975);
DISPLAY 1.021277 (-2450 1975);
PAINT ORANGE (-2450 1975);
DISPLAY INVISIBLE (-2450 1975);
FORCEPROP 2 LAST ROOM BMC_DEBUG_HEADER
J 0
(-2450 1925);
DISPLAY 1.021277 (-2450 1925);
PAINT ORANGE (-2450 1925);
DISPLAY INVISIBLE (-2450 1925);
FORCEPROP 1 LAST PATH I196
J 0
(-2450 1925);
DISPLAY 0.978723 (-2450 1925);
PAINT WHITE (-2450 1925);
DISPLAY INVISIBLE (-2450 1925);
FORCEPROP 2 LAST CDS_LIB mstr_discrete
J 0
(-2400 1775);
PAINT MONO (-2400 1775);
DISPLAY INVISIBLE (-2400 1775);
FORCEPROP 1 LAST MATERIAL CHIP
J 0
(-2400 1625);
DISPLAY 0.617021 (-2400 1625);
PAINT SKYBLUE (-2400 1625);
FORCEPROP 1 LAST TOLERANCE 5%
J 0
(-2400 1675);
DISPLAY 0.617021 (-2400 1675);
PAINT SKYBLUE (-2400 1675);
FORCEPROP 1 LAST LOCATION R6W19
J 0
(-2450 1825);
DISPLAY 0.617021 (-2450 1825);
PAINT AQUA (-2450 1825);
FORCEPROP 0 LAST STATUS NOPOP
J 0
(-2450 1900);
DISPLAY 1.021277 (-2450 1900);
PAINT ORANGE (-2450 1900);
FORCEPROP 1 LAST PART_NUMBER G21497-005
J 0
(-2450 1875);
DISPLAY 0.617021 (-2450 1875);
PAINT BLUE (-2450 1875);
FORCEPROP 1 LAST VALUE 0.0
J 2
(-2425 1675);
DISPLAY 0.617021 (-2425 1675);
PAINT SKYBLUE (-2425 1675);
FORCEPROP 1 LAST WATTAGE 1/16W
J 2
(-2425 1625);
DISPLAY 0.617021 (-2425 1625);
PAINT SKYBLUE (-2425 1625);
FORCEPROP 1 LAST PACK_TYPE 0402
J 0
(-2150 1625);
DISPLAY 0.617021 (-2150 1625);
PAINT SKYBLUE (-2150 1625);
FORCEADD CONN3_C95678002..1
R 2
(-5250 3050);
FORCEPROP 2 LAST CDS_LIB mstr_conn
J 2
(-5250 3050);
DISPLAY INVISIBLE (-5250 3050);
FORCEPROP 1 LAST PATH I198
J 2
(-5650 3200);
DISPLAY 0.978723 (-5650 3200);
PAINT BLUE (-5650 3200);
DISPLAY INVISIBLE (-5650 3200);
FORCEPROP 2 LAST ROOM SMBUS
J 2
(-5200 3300);
DISPLAY 1.021277 (-5200 3300);
PAINT ORANGE (-5200 3300);
DISPLAY INVISIBLE (-5200 3300);
FORCEPROP 1 LAST PACK_TYPE PIP
J 2
(-5200 3300);
DISPLAY 0.978723 (-5200 3300);
PAINT SKYBLUE (-5200 3300);
DISPLAY INVISIBLE (-5200 3300);
FORCEPROP 2 LAST BOM_COST SM_CONTROLLER
J 2
(-5200 3350);
DISPLAY 1.021277 (-5200 3350);
PAINT ORANGE (-5200 3350);
DISPLAY INVISIBLE (-5200 3350);
FORCEPROP 1 LAST LOCATION J1W1
J 2
(-5200 3250);
DISPLAY 0.617021 (-5200 3250);
PAINT AQUA (-5200 3250);
FORCEPROP 1 LAST MATERIAL CONN
J 2
(-5200 3200);
DISPLAY 0.617021 (-5200 3200);
PAINT SKYBLUE (-5200 3200);
FORCEPROP 1 LAST PART_NUMBER C95678-002
J 2
(-5200 2925);
DISPLAY 0.617021 (-5200 2925);
PAINT BLUE (-5200 2925);
FORCEADD P5V_STBY..1
(-4950 2950);
FORCEPROP 3 LASTPIN (-4950 2900) SIG_NAME P5V_STBY\g
J 0
(-4940 2910);
DISPLAY 0.659574 (-4940 2910);
PAINT MONO (-4940 2910);
DISPLAY INVISIBLE (-4940 2910);
FORCEPROP 2 LAST CDS_LIB mstr_symbols
J 0
(-4950 2950);
PAINT ORANGE (-4950 2950);
DISPLAY INVISIBLE (-4950 2950);
FORCEPROP 1 LAST SIZE 1B
J 0
(-4905 2972);
DISPLAY 0.340426 (-4905 2972);
PAINT GREEN (-4905 2972);
DISPLAY INVISIBLE (-4905 2972);
FORCEPROP 1 LAST VOLTAGE 5.0V
J 0
(-4995 2907);
DISPLAY 0.340426 (-4995 2907);
PAINT SKYBLUE (-4995 2907);
DISPLAY INVISIBLE (-4995 2907);
FORCEPROP 1 LAST BODY_TYPE PLUMBING
J 0
(-4995 2907);
DISPLAY 0.340426 (-4995 2907);
PAINT GREEN (-4995 2907);
DISPLAY INVISIBLE (-4995 2907);
FORCEPROP 1 LAST HDL_POWER P5V_STBY
J 0
(-5250 2825);
DISPLAY 0.872340 (-5250 2825);
PAINT ORANGE (-5250 2825);
DISPLAY INVISIBLE (-5250 2825);
FORCEPROP 1 LAST PATH I199
J 0
(-4905 2952);
DISPLAY 0.340426 (-4905 2952);
PAINT GREEN (-4905 2952);
DISPLAY INVISIBLE (-4905 2952);
FORCEADD P5V..1
(-5500 3300);
FORCEPROP 3 LASTPIN (-5500 3250) SIG_NAME P5V\g
J 0
(-5490 3260);
DISPLAY 0.659574 (-5490 3260);
PAINT MONO (-5490 3260);
DISPLAY INVISIBLE (-5490 3260);
FORCEPROP 2 LAST CDS_LIB mstr_symbols
J 0
(-5500 3300);
DISPLAY INVISIBLE (-5500 3300);
FORCEPROP 1 LAST PATH I200
J 0
(-5455 3302);
DISPLAY 0.340426 (-5455 3302);
PAINT GREEN (-5455 3302);
DISPLAY INVISIBLE (-5455 3302);
FORCEPROP 1 LAST HDL_POWER P5V
J 0
(-5800 3175);
DISPLAY 0.872340 (-5800 3175);
PAINT ORANGE (-5800 3175);
DISPLAY INVISIBLE (-5800 3175);
FORCEPROP 1 LAST BODY_TYPE PLUMBING
J 0
(-5545 3257);
DISPLAY 0.340426 (-5545 3257);
PAINT GREEN (-5545 3257);
DISPLAY INVISIBLE (-5545 3257);
FORCEPROP 1 LAST SIZE 1B
J 0
(-5455 3322);
DISPLAY 0.340426 (-5455 3322);
PAINT GREEN (-5455 3322);
DISPLAY INVISIBLE (-5455 3322);
FORCEPROP 1 LAST VOLTAGE 5.0V
J 0
(-5545 3257);
DISPLAY 0.340426 (-5545 3257);
PAINT SKYBLUE (-5545 3257);
DISPLAY INVISIBLE (-5545 3257);
FORCEADD OFFPAGE..4
(-3675 1600);
FORCEPROP 1 LAST OFFPAGE TRUE
J 0
(-3350 1475);
DISPLAY 0.872340 (-3350 1475);
PAINT GREEN (-3350 1475);
DISPLAY INVISIBLE (-3350 1475);
FORCEPROP 1 LAST COMMENT_BODY TRUE
J 0
(-3700 1500);
DISPLAY 0.872340 (-3700 1500);
PAINT GREEN (-3700 1500);
DISPLAY INVISIBLE (-3700 1500);
FORCEPROP 2 LAST CDS_LIB mstr_standard
J 0
(-3675 1600);
PAINT ORANGE (-3675 1600);
DISPLAY INVISIBLE (-3675 1600);
FORCEPROP 2 LAST PATH I31
J 0
(-3450 1650);
DISPLAY 1.021277 (-3450 1650);
PAINT ORANGE (-3450 1650);
DISPLAY INVISIBLE (-3450 1650);
FORCEPROP 2 LAST $XR1 247 
J 0
(-3489 1600);
DISPLAY 0.638298 (-3489 1600);
PAINT MONO (-3489 1600);
FORCEPROP 2 LAST $XR0 155 
J 0
(-3489 1600);
DISPLAY 0.638298 (-3489 1600);
PAINT MONO (-3489 1600);
FORCEADD OFFPAGE..4
(-3675 1550);
FORCEPROP 1 LAST COMMENT_BODY TRUE
J 0
(-3700 1450);
DISPLAY 0.872340 (-3700 1450);
PAINT GREEN (-3700 1450);
DISPLAY INVISIBLE (-3700 1450);
FORCEPROP 1 LAST OFFPAGE TRUE
J 0
(-3350 1425);
DISPLAY 0.872340 (-3350 1425);
PAINT GREEN (-3350 1425);
DISPLAY INVISIBLE (-3350 1425);
FORCEPROP 2 LAST CDS_LIB mstr_standard
J 0
(-3675 1550);
PAINT ORANGE (-3675 1550);
DISPLAY INVISIBLE (-3675 1550);
FORCEPROP 2 LAST PATH I32
J 0
(-3450 1600);
DISPLAY 1.021277 (-3450 1600);
PAINT ORANGE (-3450 1600);
DISPLAY INVISIBLE (-3450 1600);
FORCEPROP 2 LAST $XR0 155 
J 0
(-3489 1550);
DISPLAY 0.638298 (-3489 1550);
PAINT MONO (-3489 1550);
FORCEPROP 2 LAST $XR1 247 
J 0
(-3489 1550);
DISPLAY 0.638298 (-3489 1550);
PAINT MONO (-3489 1550);
FORCEADD OFFPAGE..4
(-3675 1500);
FORCEPROP 1 LAST COMMENT_BODY TRUE
J 0
(-3700 1400);
DISPLAY 0.872340 (-3700 1400);
PAINT GREEN (-3700 1400);
DISPLAY INVISIBLE (-3700 1400);
FORCEPROP 1 LAST OFFPAGE TRUE
J 0
(-3350 1375);
DISPLAY 0.872340 (-3350 1375);
PAINT GREEN (-3350 1375);
DISPLAY INVISIBLE (-3350 1375);
FORCEPROP 2 LAST CDS_LIB mstr_standard
J 0
(-3675 1500);
PAINT ORANGE (-3675 1500);
DISPLAY INVISIBLE (-3675 1500);
FORCEPROP 2 LAST PATH I33
J 0
(-3450 1550);
DISPLAY 1.021277 (-3450 1550);
PAINT ORANGE (-3450 1550);
DISPLAY INVISIBLE (-3450 1550);
FORCEPROP 2 LAST $XR1 247 
J 0
(-3489 1500);
DISPLAY 0.638298 (-3489 1500);
PAINT MONO (-3489 1500);
FORCEPROP 2 LAST $XR0 155 
J 0
(-3489 1500);
DISPLAY 0.638298 (-3489 1500);
PAINT MONO (-3489 1500);
FORCEADD OFFPAGE..4
(-3675 1450);
FORCEPROP 2 LAST $XR0 155 
J 0
(-3414 1450);
DISPLAY 0.638298 (-3414 1450);
PAINT MONO (-3414 1450);
FORCEPROP 1 LAST COMMENT_BODY TRUE
J 0
(-3700 1350);
DISPLAY 0.872340 (-3700 1350);
PAINT GREEN (-3700 1350);
DISPLAY INVISIBLE (-3700 1350);
FORCEPROP 2 LAST CDS_LIB mstr_standard
J 0
(-3675 1450);
PAINT ORANGE (-3675 1450);
DISPLAY INVISIBLE (-3675 1450);
FORCEPROP 1 LAST OFFPAGE TRUE
J 0
(-3350 1325);
DISPLAY 0.872340 (-3350 1325);
PAINT GREEN (-3350 1325);
DISPLAY INVISIBLE (-3350 1325);
FORCEPROP 2 LAST PATH I34
J 0
(-3450 1500);
DISPLAY 1.021277 (-3450 1500);
PAINT ORANGE (-3450 1500);
DISPLAY INVISIBLE (-3450 1500);
FORCEPROP 2 LAST $XR1 247 
J 0
(-3489 1450);
DISPLAY 0.638298 (-3489 1450);
PAINT MONO (-3489 1450);
FORCEADD OFFPAGE..1
(-5450 1600);
FORCEPROP 2 LAST CDS_LIB mstr_standard
J 0
(-5450 1600);
PAINT ORANGE (-5450 1600);
DISPLAY INVISIBLE (-5450 1600);
FORCEPROP 2 LAST PATH I37
J 0
(-5900 1650);
DISPLAY 1.021277 (-5900 1650);
PAINT ORANGE (-5900 1650);
DISPLAY INVISIBLE (-5900 1650);
FORCEPROP 1 LAST COMMENT_BODY TRUE
J 0
(-5325 1500);
DISPLAY 0.872340 (-5325 1500);
PAINT GREEN (-5325 1500);
DISPLAY INVISIBLE (-5325 1500);
FORCEPROP 1 LAST OFFPAGE TRUE
J 0
(-5125 1475);
DISPLAY 0.872340 (-5125 1475);
PAINT GREEN (-5125 1475);
DISPLAY INVISIBLE (-5125 1475);
FORCEPROP 2 LAST $XR1 247 
J 0
(-5827 1600);
DISPLAY 0.638298 (-5827 1600);
PAINT MONO (-5827 1600);
FORCEPROP 2 LAST $XR0 155 
J 0
(-5727 1600);
DISPLAY 0.638298 (-5727 1600);
PAINT MONO (-5727 1600);
FORCEADD OFFPAGE..1
(-5450 1550);
FORCEPROP 2 LAST CDS_LIB mstr_standard
J 0
(-5450 1550);
PAINT ORANGE (-5450 1550);
DISPLAY INVISIBLE (-5450 1550);
FORCEPROP 2 LAST PATH I38
J 0
(-5725 1600);
DISPLAY 1.021277 (-5725 1600);
PAINT ORANGE (-5725 1600);
DISPLAY INVISIBLE (-5725 1600);
FORCEPROP 1 LAST OFFPAGE TRUE
J 0
(-5125 1425);
DISPLAY 0.872340 (-5125 1425);
PAINT GREEN (-5125 1425);
DISPLAY INVISIBLE (-5125 1425);
FORCEPROP 1 LAST COMMENT_BODY TRUE
J 0
(-5325 1450);
DISPLAY 0.872340 (-5325 1450);
PAINT GREEN (-5325 1450);
DISPLAY INVISIBLE (-5325 1450);
FORCEPROP 2 LAST $XR0 155 
J 0
(-5727 1550);
DISPLAY 0.638298 (-5727 1550);
PAINT MONO (-5727 1550);
FORCEPROP 2 LAST $XR1 247 
J 0
(-5827 1550);
DISPLAY 0.638298 (-5827 1550);
PAINT MONO (-5827 1550);
FORCEADD OFFPAGE..1
(-5450 1500);
FORCEPROP 2 LAST PATH I39
J 0
(-5725 1550);
DISPLAY 1.021277 (-5725 1550);
PAINT ORANGE (-5725 1550);
DISPLAY INVISIBLE (-5725 1550);
FORCEPROP 2 LAST CDS_LIB mstr_standard
J 0
(-5450 1500);
PAINT ORANGE (-5450 1500);
DISPLAY INVISIBLE (-5450 1500);
FORCEPROP 1 LAST OFFPAGE TRUE
J 0
(-5125 1375);
DISPLAY 0.872340 (-5125 1375);
PAINT GREEN (-5125 1375);
DISPLAY INVISIBLE (-5125 1375);
FORCEPROP 1 LAST COMMENT_BODY TRUE
J 0
(-5325 1400);
DISPLAY 0.872340 (-5325 1400);
PAINT GREEN (-5325 1400);
DISPLAY INVISIBLE (-5325 1400);
FORCEPROP 2 LAST $XR1 247 
J 0
(-5827 1500);
DISPLAY 0.638298 (-5827 1500);
PAINT MONO (-5827 1500);
FORCEPROP 2 LAST $XR0 155 
J 0
(-5727 1500);
DISPLAY 0.638298 (-5727 1500);
PAINT MONO (-5727 1500);
FORCEADD OFFPAGE..1
(-5450 1450);
FORCEPROP 2 LAST PATH I40
J 0
(-5725 1500);
DISPLAY 1.021277 (-5725 1500);
PAINT ORANGE (-5725 1500);
DISPLAY INVISIBLE (-5725 1500);
FORCEPROP 1 LAST OFFPAGE TRUE
J 0
(-5125 1325);
DISPLAY 0.872340 (-5125 1325);
PAINT GREEN (-5125 1325);
DISPLAY INVISIBLE (-5125 1325);
FORCEPROP 1 LAST COMMENT_BODY TRUE
J 0
(-5325 1350);
DISPLAY 0.872340 (-5325 1350);
PAINT GREEN (-5325 1350);
DISPLAY INVISIBLE (-5325 1350);
FORCEPROP 2 LAST CDS_LIB mstr_standard
J 0
(-5450 1450);
PAINT ORANGE (-5450 1450);
DISPLAY INVISIBLE (-5450 1450);
FORCEPROP 2 LAST $XR0 155 
J 0
(-5727 1450);
DISPLAY 0.638298 (-5727 1450);
PAINT MONO (-5727 1450);
FORCEPROP 2 LAST $XR1 247 
J 0
(-5827 1450);
DISPLAY 0.638298 (-5827 1450);
PAINT MONO (-5827 1450);
FORCEADD GND..1
(-4825 1125);
FORCEPROP 3 LASTPIN (-4825 1175) SIG_NAME GND\g
J 0
(-4815 1185);
DISPLAY 0.659574 (-4815 1185);
PAINT MONO (-4815 1185);
DISPLAY INVISIBLE (-4815 1185);
FORCEPROP 1 LAST VOLTAGE 0.0V
J 0
(-4870 1082);
DISPLAY 0.340426 (-4870 1082);
PAINT SKYBLUE (-4870 1082);
DISPLAY INVISIBLE (-4870 1082);
FORCEPROP 2 LAST CDS_LIB mstr_symbols
J 0
(-4825 1125);
PAINT ORANGE (-4825 1125);
DISPLAY INVISIBLE (-4825 1125);
FORCEPROP 1 LAST BODY_TYPE PLUMBING
J 0
(-4870 1082);
DISPLAY 0.340426 (-4870 1082);
PAINT GREEN (-4870 1082);
DISPLAY INVISIBLE (-4870 1082);
FORCEPROP 1 LAST HDL_POWER GND
J 0
(-4825 1275);
DISPLAY 0.872340 (-4825 1275);
PAINT GREEN (-4825 1275);
DISPLAY INVISIBLE (-4825 1275);
FORCEPROP 1 LAST SIZE 1B
J 0
(-4750 1075);
DISPLAY 0.872340 (-4750 1075);
PAINT AQUA (-4750 1075);
DISPLAY INVISIBLE (-4750 1075);
FORCEPROP 1 LAST PATH I41
J 0
(-4750 1125);
DISPLAY 0.872340 (-4750 1125);
PAINT AQUA (-4750 1125);
DISPLAY INVISIBLE (-4750 1125);
FORCEADD OFFPAGE..5
(-5475 1350);
FORCEPROP 2 LAST PATH I42
J 0
(-5675 1400);
DISPLAY 1.021277 (-5675 1400);
PAINT ORANGE (-5675 1400);
DISPLAY INVISIBLE (-5675 1400);
FORCEPROP 2 LAST CDS_LIB mstr_standard
J 0
(-5475 1350);
PAINT ORANGE (-5475 1350);
DISPLAY INVISIBLE (-5475 1350);
FORCEPROP 1 LAST COMMENT_BODY TRUE
J 0
(-5375 1275);
DISPLAY 0.872340 (-5375 1275);
PAINT GREEN (-5375 1275);
DISPLAY INVISIBLE (-5375 1275);
FORCEPROP 1 LAST OFFPAGE TRUE
J 0
(-5150 1225);
DISPLAY 0.872340 (-5150 1225);
PAINT GREEN (-5150 1225);
DISPLAY INVISIBLE (-5150 1225);
FORCEPROP 2 LAST $XR3 175 
J 0
(-6070 1350);
DISPLAY 0.638298 (-6070 1350);
PAINT MONO (-6070 1350);
FORCEPROP 2 LAST $XR0 111 
J 0
(-5730 1350);
DISPLAY 0.638298 (-5730 1350);
PAINT MONO (-5730 1350);
FORCEPROP 2 LAST $XR1 190 
J 0
(-5850 1350);
DISPLAY 0.638298 (-5850 1350);
PAINT MONO (-5850 1350);
FORCEPROP 2 LAST $XR2 247 
J 0
(-5970 1350);
DISPLAY 0.638298 (-5970 1350);
PAINT MONO (-5970 1350);
FORCEADD OFFPAGE..1
(-5450 1400);
FORCEPROP 1 LAST OFFPAGE TRUE
J 0
(-5125 1275);
DISPLAY 0.872340 (-5125 1275);
PAINT GREEN (-5125 1275);
DISPLAY INVISIBLE (-5125 1275);
FORCEPROP 1 LAST COMMENT_BODY TRUE
J 0
(-5325 1300);
DISPLAY 0.872340 (-5325 1300);
PAINT GREEN (-5325 1300);
DISPLAY INVISIBLE (-5325 1300);
FORCEPROP 2 LAST CDS_LIB mstr_standard
J 0
(-5450 1400);
PAINT ORANGE (-5450 1400);
DISPLAY INVISIBLE (-5450 1400);
FORCEPROP 2 LAST PATH I43
J 0
(-5725 1450);
DISPLAY 1.021277 (-5725 1450);
PAINT ORANGE (-5725 1450);
DISPLAY INVISIBLE (-5725 1450);
FORCEPROP 2 LAST $XR0 158 
J 0
(-5732 1400);
DISPLAY 0.638298 (-5732 1400);
PAINT MONO (-5732 1400);
FORCEPROP 2 LAST $XR1 176 
J 0
(-5852 1400);
DISPLAY 0.638298 (-5852 1400);
PAINT MONO (-5852 1400);
FORCEPROP 2 LAST $XR2 181 
J 0
(-5852 1400);
DISPLAY 0.638298 (-5852 1400);
PAINT MONO (-5852 1400);
FORCEADD OFFPAGE..2
(-900 1400);
FORCEPROP 1 LAST OFFPAGE TRUE
J 0
(-575 1275);
DISPLAY 0.872340 (-575 1275);
PAINT GREEN (-575 1275);
DISPLAY INVISIBLE (-575 1275);
FORCEPROP 2 LAST PATH I52
J 0
(-700 1450);
DISPLAY 1.021277 (-700 1450);
PAINT ORANGE (-700 1450);
DISPLAY INVISIBLE (-700 1450);
FORCEPROP 2 LAST CDS_LIB mstr_standard
J 0
(-900 1400);
PAINT ORANGE (-900 1400);
DISPLAY INVISIBLE (-900 1400);
FORCEPROP 1 LAST COMMENT_BODY TRUE
J 0
(-945 1305);
DISPLAY 0.872340 (-945 1305);
PAINT GREEN (-945 1305);
DISPLAY INVISIBLE (-945 1305);
FORCEPROP 2 LAST $XR0 176 
J 0
(-711 1400);
DISPLAY 0.638298 (-711 1400);
PAINT MONO (-711 1400);
FORCEPROP 2 LAST $XR1 ?
J 0
(-591 1400);
DISPLAY 0.638298 (-591 1400);
PAINT MONO (-591 1400);
FORCEADD RES..1
(-1575 1400);
FORCEPROP 2 LAST BOM_COST DEBUG
J 0
(-1625 1600);
DISPLAY 1.021277 (-1625 1600);
PAINT ORANGE (-1625 1600);
DISPLAY INVISIBLE (-1625 1600);
FORCEPROP 2 LAST SEC_TYPE 0402
J 0
(-1625 1600);
DISPLAY 1.021277 (-1625 1600);
PAINT ORANGE (-1625 1600);
DISPLAY INVISIBLE (-1625 1600);
FORCEPROP 2 LAST SEC 1
J 0
(-1625 1600);
PAINT MONO (-1625 1600);
DISPLAY INVISIBLE (-1625 1600);
FORCEPROP 1 LAST PATH I53
J 0
(-1625 1550);
DISPLAY 0.978723 (-1625 1550);
PAINT WHITE (-1625 1550);
DISPLAY INVISIBLE (-1625 1550);
FORCEPROP 2 LAST ROOM BMC_DEBUG_HEADER
J 0
(-1625 1550);
DISPLAY 1.021277 (-1625 1550);
PAINT ORANGE (-1625 1550);
DISPLAY INVISIBLE (-1625 1550);
FORCEPROP 2 LAST CDS_LIB mstr_discrete
J 0
(-1575 1400);
PAINT ORANGE (-1575 1400);
DISPLAY INVISIBLE (-1575 1400);
FORCEPROP 2 LAST CDS_LOCATION R9A8
J 0
(-1625 1450);
DISPLAY 0.617021 (-1625 1450);
PAINT AQUA (-1625 1450);
DISPLAY INVISIBLE (-1625 1450);
FORCEPROP 1 LAST PACK_TYPE 0402
J 0
(-1325 1250);
DISPLAY 0.617021 (-1325 1250);
PAINT SKYBLUE (-1325 1250);
FORCEPROP 1 LAST MATERIAL CHIP
J 0
(-1575 1250);
DISPLAY 0.617021 (-1575 1250);
PAINT SKYBLUE (-1575 1250);
FORCEPROP 1 LAST VALUE 0.0
J 2
(-1600 1300);
DISPLAY 0.617021 (-1600 1300);
PAINT SKYBLUE (-1600 1300);
FORCEPROP 1 LAST WATTAGE 1/16W
J 2
(-1600 1250);
DISPLAY 0.617021 (-1600 1250);
PAINT SKYBLUE (-1600 1250);
FORCEPROP 1 LASTPIN (-1675 1400) $PN 1
J 0
(-1663 1412);
DISPLAY 0.617021 (-1663 1412);
PAINT ORANGE (-1663 1412);
FORCEPROP 1 LASTPIN (-1475 1400) $PN 2
J 0
(-1513 1412);
DISPLAY 0.617021 (-1513 1412);
PAINT ORANGE (-1513 1412);
FORCEPROP 1 LAST PART_NUMBER G21497-005
J 0
(-1625 1500);
DISPLAY 0.617021 (-1625 1500);
PAINT BLUE (-1625 1500);
FORCEPROP 1 LAST LOCATION R9A8
J 0
(-1625 1450);
DISPLAY 0.617021 (-1625 1450);
PAINT AQUA (-1625 1450);
FORCEPROP 1 LAST TOLERANCE 5%
J 0
(-1575 1300);
DISPLAY 0.617021 (-1575 1300);
PAINT SKYBLUE (-1575 1300);
FORCEADD OFFPAGE..3
(-1700 950);
FORCEPROP 1 LAST COMMENT_BODY TRUE
J 0
(-1750 850);
DISPLAY 0.872340 (-1750 850);
PAINT GREEN (-1750 850);
DISPLAY INVISIBLE (-1750 850);
FORCEPROP 2 LAST CDS_LIB mstr_standard
J 0
(-1700 950);
PAINT ORANGE (-1700 950);
DISPLAY INVISIBLE (-1700 950);
FORCEPROP 1 LAST OFFPAGE TRUE
J 0
(-1375 825);
DISPLAY 0.872340 (-1375 825);
PAINT GREEN (-1375 825);
DISPLAY INVISIBLE (-1375 825);
FORCEPROP 2 LAST PATH I55
J 0
(-1500 1025);
DISPLAY 1.021277 (-1500 1025);
PAINT ORANGE (-1500 1025);
DISPLAY INVISIBLE (-1500 1025);
FORCEPROP 2 LAST $XR1 168 
J 0
(-1486 950);
DISPLAY 0.638298 (-1486 950);
PAINT MONO (-1486 950);
FORCEPROP 2 LAST $XR0 176 
J 0
(-1486 950);
DISPLAY 0.638298 (-1486 950);
PAINT MONO (-1486 950);
FORCEADD OFFPAGE..1
(-7475 4050);
FORCEPROP 2 LAST $XR1 146 
J 0
(-7847 4050);
DISPLAY 0.638298 (-7847 4050);
PAINT MONO (-7847 4050);
FORCEPROP 2 LAST $XR0 120 
J 0
(-7727 4050);
DISPLAY 0.638298 (-7727 4050);
PAINT MONO (-7727 4050);
FORCEPROP 2 LAST PATH I56
J 0
(-7725 4100);
DISPLAY 1.021277 (-7725 4100);
PAINT ORANGE (-7725 4100);
DISPLAY INVISIBLE (-7725 4100);
FORCEPROP 1 LAST OFFPAGE TRUE
J 0
(-7150 3925);
DISPLAY 0.872340 (-7150 3925);
PAINT GREEN (-7150 3925);
DISPLAY INVISIBLE (-7150 3925);
FORCEPROP 1 LAST COMMENT_BODY TRUE
J 0
(-7350 3950);
DISPLAY 0.872340 (-7350 3950);
PAINT GREEN (-7350 3950);
DISPLAY INVISIBLE (-7350 3950);
FORCEPROP 2 LAST CDS_LIB mstr_standard
J 0
(-7475 4050);
PAINT ORANGE (-7475 4050);
DISPLAY INVISIBLE (-7475 4050);
FORCEADD OFFPAGE..1
(-7475 3900);
FORCEPROP 2 LAST $XR1 146 
J 0
(-7847 3900);
DISPLAY 0.638298 (-7847 3900);
PAINT MONO (-7847 3900);
FORCEPROP 2 LAST $XR0 120 
J 0
(-7727 3900);
DISPLAY 0.638298 (-7727 3900);
PAINT MONO (-7727 3900);
FORCEPROP 1 LAST OFFPAGE TRUE
J 0
(-7150 3775);
DISPLAY 0.872340 (-7150 3775);
PAINT GREEN (-7150 3775);
DISPLAY INVISIBLE (-7150 3775);
FORCEPROP 1 LAST COMMENT_BODY TRUE
J 0
(-7350 3800);
DISPLAY 0.872340 (-7350 3800);
PAINT GREEN (-7350 3800);
DISPLAY INVISIBLE (-7350 3800);
FORCEPROP 2 LAST CDS_LIB mstr_standard
J 0
(-7475 3900);
PAINT ORANGE (-7475 3900);
DISPLAY INVISIBLE (-7475 3900);
FORCEPROP 2 LAST PATH I57
J 0
(-7725 3950);
DISPLAY 1.021277 (-7725 3950);
PAINT ORANGE (-7725 3950);
DISPLAY INVISIBLE (-7725 3950);
FORCEADD OFFPAGE..1
(-7475 3750);
FORCEPROP 2 LAST $XR1 146 
J 0
(-7847 3750);
DISPLAY 0.638298 (-7847 3750);
PAINT MONO (-7847 3750);
FORCEPROP 2 LAST $XR0 120 
J 0
(-7727 3750);
DISPLAY 0.638298 (-7727 3750);
PAINT MONO (-7727 3750);
FORCEPROP 1 LAST OFFPAGE TRUE
J 0
(-7150 3625);
DISPLAY 0.872340 (-7150 3625);
PAINT GREEN (-7150 3625);
DISPLAY INVISIBLE (-7150 3625);
FORCEPROP 1 LAST COMMENT_BODY TRUE
J 0
(-7350 3650);
DISPLAY 0.872340 (-7350 3650);
PAINT GREEN (-7350 3650);
DISPLAY INVISIBLE (-7350 3650);
FORCEPROP 2 LAST CDS_LIB mstr_standard
J 0
(-7475 3750);
PAINT ORANGE (-7475 3750);
DISPLAY INVISIBLE (-7475 3750);
FORCEPROP 2 LAST PATH I58
J 0
(-7725 3800);
DISPLAY 1.021277 (-7725 3800);
PAINT ORANGE (-7725 3800);
DISPLAY INVISIBLE (-7725 3800);
FORCEADD OFFPAGE..1
(-7475 3600);
FORCEPROP 2 LAST $XR1 146 
J 0
(-7847 3600);
DISPLAY 0.638298 (-7847 3600);
PAINT MONO (-7847 3600);
FORCEPROP 2 LAST $XR0 120 
J 0
(-7727 3600);
DISPLAY 0.638298 (-7727 3600);
PAINT MONO (-7727 3600);
FORCEPROP 1 LAST OFFPAGE TRUE
J 0
(-7150 3475);
DISPLAY 0.872340 (-7150 3475);
PAINT GREEN (-7150 3475);
DISPLAY INVISIBLE (-7150 3475);
FORCEPROP 1 LAST COMMENT_BODY TRUE
J 0
(-7350 3500);
DISPLAY 0.872340 (-7350 3500);
PAINT GREEN (-7350 3500);
DISPLAY INVISIBLE (-7350 3500);
FORCEPROP 2 LAST PATH I59
J 0
(-7725 3650);
DISPLAY 1.021277 (-7725 3650);
PAINT ORANGE (-7725 3650);
DISPLAY INVISIBLE (-7725 3650);
FORCEPROP 2 LAST CDS_LIB mstr_standard
J 0
(-7475 3600);
PAINT ORANGE (-7475 3600);
DISPLAY INVISIBLE (-7475 3600);
FORCEADD OFFPAGE..1
(-7475 4200);
FORCEPROP 2 LAST $XR1 146 
J 0
(-7847 4200);
DISPLAY 0.638298 (-7847 4200);
PAINT MONO (-7847 4200);
FORCEPROP 2 LAST $XR0 120 
J 0
(-7727 4200);
DISPLAY 0.638298 (-7727 4200);
PAINT MONO (-7727 4200);
FORCEPROP 2 LAST CDS_LIB mstr_standard
J 0
(-7475 4200);
PAINT ORANGE (-7475 4200);
DISPLAY INVISIBLE (-7475 4200);
FORCEPROP 2 LAST PATH I60
J 0
(-7725 4250);
DISPLAY 1.021277 (-7725 4250);
PAINT ORANGE (-7725 4250);
DISPLAY INVISIBLE (-7725 4250);
FORCEPROP 1 LAST COMMENT_BODY TRUE
J 0
(-7350 4100);
DISPLAY 0.872340 (-7350 4100);
PAINT GREEN (-7350 4100);
DISPLAY INVISIBLE (-7350 4100);
FORCEPROP 1 LAST OFFPAGE TRUE
J 0
(-7150 4075);
DISPLAY 0.872340 (-7150 4075);
PAINT GREEN (-7150 4075);
DISPLAY INVISIBLE (-7150 4075);
FORCEADD OFFPAGE..2
(-6050 3600);
FORCEPROP 2 LAST $XR1 155 
J 0
(-5861 3600);
DISPLAY 0.638298 (-5861 3600);
PAINT MONO (-5861 3600);
FORCEPROP 2 LAST $XR0 247 
J 0
(-5861 3600);
DISPLAY 0.638298 (-5861 3600);
PAINT MONO (-5861 3600);
FORCEPROP 2 LAST PATH I61
J 0
(-5825 3650);
DISPLAY 1.021277 (-5825 3650);
PAINT ORANGE (-5825 3650);
DISPLAY INVISIBLE (-5825 3650);
FORCEPROP 1 LAST OFFPAGE TRUE
J 0
(-5725 3475);
DISPLAY 0.872340 (-5725 3475);
PAINT GREEN (-5725 3475);
DISPLAY INVISIBLE (-5725 3475);
FORCEPROP 2 LAST CDS_LIB mstr_standard
J 0
(-6050 3600);
PAINT ORANGE (-6050 3600);
DISPLAY INVISIBLE (-6050 3600);
FORCEPROP 1 LAST COMMENT_BODY TRUE
J 0
(-6095 3505);
DISPLAY 0.872340 (-6095 3505);
PAINT GREEN (-6095 3505);
DISPLAY INVISIBLE (-6095 3505);
FORCEADD OFFPAGE..2
(-6050 4350);
FORCEPROP 2 LAST $XR1 155 
J 0
(-5861 4350);
DISPLAY 0.638298 (-5861 4350);
PAINT MONO (-5861 4350);
FORCEPROP 2 LAST $XR0 247 
J 0
(-5861 4350);
DISPLAY 0.638298 (-5861 4350);
PAINT MONO (-5861 4350);
FORCEPROP 1 LAST OFFPAGE TRUE
J 0
(-5725 4225);
DISPLAY 0.872340 (-5725 4225);
PAINT GREEN (-5725 4225);
DISPLAY INVISIBLE (-5725 4225);
FORCEPROP 2 LAST PATH I62
J 0
(-5825 4400);
DISPLAY 1.021277 (-5825 4400);
PAINT ORANGE (-5825 4400);
DISPLAY INVISIBLE (-5825 4400);
FORCEPROP 2 LAST CDS_LIB mstr_standard
J 0
(-6050 4350);
PAINT ORANGE (-6050 4350);
DISPLAY INVISIBLE (-6050 4350);
FORCEPROP 1 LAST COMMENT_BODY TRUE
J 0
(-6095 4255);
DISPLAY 0.872340 (-6095 4255);
PAINT GREEN (-6095 4255);
DISPLAY INVISIBLE (-6095 4255);
FORCEADD OFFPAGE..2
(-6050 4500);
FORCEPROP 2 LAST $XR1 155 
J 0
(-5861 4500);
DISPLAY 0.638298 (-5861 4500);
PAINT MONO (-5861 4500);
FORCEPROP 2 LAST $XR0 247 
J 0
(-5861 4500);
DISPLAY 0.638298 (-5861 4500);
PAINT MONO (-5861 4500);
FORCEPROP 1 LAST OFFPAGE TRUE
J 0
(-5725 4375);
DISPLAY 0.872340 (-5725 4375);
PAINT GREEN (-5725 4375);
DISPLAY INVISIBLE (-5725 4375);
FORCEPROP 2 LAST PATH I63
J 0
(-5825 4550);
DISPLAY 1.021277 (-5825 4550);
PAINT ORANGE (-5825 4550);
DISPLAY INVISIBLE (-5825 4550);
FORCEPROP 2 LAST CDS_LIB mstr_standard
J 0
(-6050 4500);
PAINT ORANGE (-6050 4500);
DISPLAY INVISIBLE (-6050 4500);
FORCEPROP 1 LAST COMMENT_BODY TRUE
J 0
(-6095 4405);
DISPLAY 0.872340 (-6095 4405);
PAINT GREEN (-6095 4405);
DISPLAY INVISIBLE (-6095 4405);
FORCEADD OFFPAGE..2
(-6050 4650);
FORCEPROP 2 LAST $XR1 155 
J 0
(-5861 4650);
DISPLAY 0.638298 (-5861 4650);
PAINT MONO (-5861 4650);
FORCEPROP 2 LAST $XR0 247 
J 0
(-5861 4650);
DISPLAY 0.638298 (-5861 4650);
PAINT MONO (-5861 4650);
FORCEPROP 1 LAST OFFPAGE TRUE
J 0
(-5725 4525);
DISPLAY 0.872340 (-5725 4525);
PAINT GREEN (-5725 4525);
DISPLAY INVISIBLE (-5725 4525);
FORCEPROP 2 LAST PATH I64
J 0
(-5825 4700);
DISPLAY 1.021277 (-5825 4700);
PAINT ORANGE (-5825 4700);
DISPLAY INVISIBLE (-5825 4700);
FORCEPROP 2 LAST CDS_LIB mstr_standard
J 0
(-6050 4650);
PAINT ORANGE (-6050 4650);
DISPLAY INVISIBLE (-6050 4650);
FORCEPROP 1 LAST COMMENT_BODY TRUE
J 0
(-6095 4555);
DISPLAY 0.872340 (-6095 4555);
PAINT GREEN (-6095 4555);
DISPLAY INVISIBLE (-6095 4555);
FORCEADD RES..1
(-6900 4650);
FORCEPROP 1 LAST PART_NUMBER G21796-066
J 0
(-6800 4675);
DISPLAY 0.617021 (-6800 4675);
PAINT BLUE (-6800 4675);
FORCEPROP 1 LASTPIN (-6800 4650) $PN 2
J 0
(-6838 4662);
DISPLAY 0.617021 (-6838 4662);
PAINT ORANGE (-6838 4662);
FORCEPROP 1 LAST PACK_TYPE 0402
J 0
(-6750 4600);
DISPLAY 0.617021 (-6750 4600);
PAINT SKYBLUE (-6750 4600);
FORCEPROP 1 LAST TOLERANCE 1%
J 0
(-6850 4600);
DISPLAY 0.617021 (-6850 4600);
PAINT SKYBLUE (-6850 4600);
FORCEPROP 1 LAST LOCATION R1L32
J 0
(-6950 4700);
DISPLAY 0.617021 (-6950 4700);
PAINT AQUA (-6950 4700);
FORCEPROP 1 LAST VALUE 10.0
J 2
(-6925 4600);
DISPLAY 0.617021 (-6925 4600);
PAINT SKYBLUE (-6925 4600);
FORCEPROP 1 LASTPIN (-7000 4650) $PN 1
J 0
(-6988 4662);
DISPLAY 0.617021 (-6988 4662);
PAINT ORANGE (-6988 4662);
FORCEPROP 1 LAST WATTAGE 1/16W
J 2
(-7025 4600);
DISPLAY 0.617021 (-7025 4600);
PAINT SKYBLUE (-7025 4600);
FORCEPROP 2 LAST CDS_LIB mstr_discrete
J 0
(-6900 4650);
PAINT ORANGE (-6900 4650);
DISPLAY INVISIBLE (-6900 4650);
FORCEPROP 1 LAST MATERIAL CHIP
J 0
(-6900 4500);
DISPLAY 0.978723 (-6900 4500);
PAINT SKYBLUE (-6900 4500);
DISPLAY INVISIBLE (-6900 4500);
FORCEPROP 2 LAST ROOM BMC_DEBUG_HEADER
J 0
(-6950 4750);
DISPLAY 1.021277 (-6950 4750);
PAINT ORANGE (-6950 4750);
DISPLAY INVISIBLE (-6950 4750);
FORCEPROP 1 LAST PATH I65
J 0
(-6950 4800);
DISPLAY 0.978723 (-6950 4800);
PAINT WHITE (-6950 4800);
DISPLAY INVISIBLE (-6950 4800);
FORCEPROP 2 LAST CDS_LOCATION R1L32
J 0
(-6950 4700);
DISPLAY 0.617021 (-6950 4700);
PAINT AQUA (-6950 4700);
DISPLAY INVISIBLE (-6950 4700);
FORCEPROP 2 LAST $SEC 1
J 0
(-6950 4850);
PAINT MONO (-6950 4850);
DISPLAY INVISIBLE (-6950 4850);
FORCEPROP 2 LAST CDS_SEC 1
J 0
(-6950 4850);
PAINT MONO (-6950 4850);
DISPLAY INVISIBLE (-6950 4850);
FORCEPROP 2 LAST BOM_COST DEBUG
J 0
(-6950 4800);
DISPLAY 1.021277 (-6950 4800);
PAINT ORANGE (-6950 4800);
DISPLAY INVISIBLE (-6950 4800);
FORCEADD RES..1
(-6900 4500);
FORCEPROP 1 LAST PART_NUMBER G21796-066
J 0
(-6800 4525);
DISPLAY 0.617021 (-6800 4525);
PAINT BLUE (-6800 4525);
FORCEPROP 1 LAST PACK_TYPE 0402
J 0
(-6750 4450);
DISPLAY 0.617021 (-6750 4450);
PAINT SKYBLUE (-6750 4450);
FORCEPROP 1 LAST TOLERANCE 1%
J 0
(-6850 4450);
DISPLAY 0.617021 (-6850 4450);
PAINT SKYBLUE (-6850 4450);
FORCEPROP 1 LASTPIN (-6800 4500) $PN 2
J 0
(-6838 4512);
DISPLAY 0.617021 (-6838 4512);
PAINT ORANGE (-6838 4512);
FORCEPROP 1 LAST LOCATION R1L30
J 0
(-6950 4550);
DISPLAY 0.617021 (-6950 4550);
PAINT AQUA (-6950 4550);
FORCEPROP 1 LAST VALUE 10.0
J 2
(-6925 4450);
DISPLAY 0.617021 (-6925 4450);
PAINT SKYBLUE (-6925 4450);
FORCEPROP 1 LAST WATTAGE 1/16W
J 2
(-7025 4450);
DISPLAY 0.617021 (-7025 4450);
PAINT SKYBLUE (-7025 4450);
FORCEPROP 1 LASTPIN (-7000 4500) $PN 1
J 0
(-6988 4512);
DISPLAY 0.617021 (-6988 4512);
PAINT ORANGE (-6988 4512);
FORCEPROP 2 LAST CDS_LIB mstr_discrete
J 0
(-6900 4500);
PAINT ORANGE (-6900 4500);
DISPLAY INVISIBLE (-6900 4500);
FORCEPROP 1 LAST MATERIAL CHIP
J 0
(-6900 4350);
DISPLAY 0.978723 (-6900 4350);
PAINT SKYBLUE (-6900 4350);
DISPLAY INVISIBLE (-6900 4350);
FORCEPROP 1 LAST PATH I66
J 0
(-6950 4650);
DISPLAY 0.978723 (-6950 4650);
PAINT WHITE (-6950 4650);
DISPLAY INVISIBLE (-6950 4650);
FORCEPROP 2 LAST $SEC 1
J 0
(-6950 4700);
PAINT MONO (-6950 4700);
DISPLAY INVISIBLE (-6950 4700);
FORCEPROP 2 LAST CDS_SEC 1
J 0
(-6950 4700);
PAINT MONO (-6950 4700);
DISPLAY INVISIBLE (-6950 4700);
FORCEPROP 2 LAST BOM_COST DEBUG
J 0
(-6950 4650);
DISPLAY 1.021277 (-6950 4650);
PAINT ORANGE (-6950 4650);
DISPLAY INVISIBLE (-6950 4650);
FORCEPROP 2 LAST ROOM BMC_DEBUG_HEADER
J 0
(-6950 4600);
DISPLAY 1.021277 (-6950 4600);
PAINT ORANGE (-6950 4600);
DISPLAY INVISIBLE (-6950 4600);
FORCEPROP 2 LAST CDS_LOCATION R1L30
J 0
(-6950 4550);
DISPLAY 0.617021 (-6950 4550);
PAINT AQUA (-6950 4550);
DISPLAY INVISIBLE (-6950 4550);
FORCEADD RES..1
(-6900 4350);
FORCEPROP 1 LAST PART_NUMBER G21796-066
J 0
(-6800 4375);
DISPLAY 0.617021 (-6800 4375);
PAINT BLUE (-6800 4375);
FORCEPROP 1 LAST PACK_TYPE 0402
J 0
(-6750 4300);
DISPLAY 0.617021 (-6750 4300);
PAINT SKYBLUE (-6750 4300);
FORCEPROP 1 LAST LOCATION R1L25
J 0
(-6900 4375);
DISPLAY 0.617021 (-6900 4375);
PAINT AQUA (-6900 4375);
FORCEPROP 1 LASTPIN (-6800 4350) $PN 2
J 0
(-6838 4362);
DISPLAY 0.617021 (-6838 4362);
PAINT ORANGE (-6838 4362);
FORCEPROP 1 LAST TOLERANCE 1%
J 0
(-6850 4300);
DISPLAY 0.617021 (-6850 4300);
PAINT SKYBLUE (-6850 4300);
FORCEPROP 1 LAST VALUE 10.0
J 2
(-6925 4300);
DISPLAY 0.617021 (-6925 4300);
PAINT SKYBLUE (-6925 4300);
FORCEPROP 1 LASTPIN (-7000 4350) $PN 1
J 0
(-6988 4362);
DISPLAY 0.617021 (-6988 4362);
PAINT ORANGE (-6988 4362);
FORCEPROP 1 LAST WATTAGE 1/16W
J 2
(-7025 4300);
DISPLAY 0.617021 (-7025 4300);
PAINT SKYBLUE (-7025 4300);
FORCEPROP 2 LAST BOM_COST DEBUG
J 0
(-6800 4475);
DISPLAY 1.021277 (-6800 4475);
PAINT ORANGE (-6800 4475);
DISPLAY INVISIBLE (-6800 4475);
FORCEPROP 2 LAST ROOM BMC_DEBUG_HEADER
J 0
(-6800 4425);
DISPLAY 1.021277 (-6800 4425);
PAINT ORANGE (-6800 4425);
DISPLAY INVISIBLE (-6800 4425);
FORCEPROP 2 LAST CDS_LIB mstr_discrete
J 0
(-6900 4350);
PAINT ORANGE (-6900 4350);
DISPLAY INVISIBLE (-6900 4350);
FORCEPROP 2 LAST CDS_LOCATION R1L25
J 0
(-6900 4375);
DISPLAY 0.617021 (-6900 4375);
PAINT AQUA (-6900 4375);
DISPLAY INVISIBLE (-6900 4375);
FORCEPROP 1 LAST MATERIAL CHIP
J 0
(-6900 4200);
DISPLAY 0.978723 (-6900 4200);
PAINT SKYBLUE (-6900 4200);
DISPLAY INVISIBLE (-6900 4200);
FORCEPROP 2 LAST CDS_SEC 1
J 0
(-6950 4550);
PAINT MONO (-6950 4550);
DISPLAY INVISIBLE (-6950 4550);
FORCEPROP 2 LAST $SEC 1
J 0
(-6950 4550);
PAINT MONO (-6950 4550);
DISPLAY INVISIBLE (-6950 4550);
FORCEPROP 1 LAST PATH I67
J 0
(-6950 4500);
DISPLAY 0.978723 (-6950 4500);
PAINT WHITE (-6950 4500);
DISPLAY INVISIBLE (-6950 4500);
FORCEADD RES..1
(-6900 4200);
FORCEPROP 1 LAST PART_NUMBER G21796-066
J 0
(-6800 4225);
DISPLAY 0.617021 (-6800 4225);
PAINT BLUE (-6800 4225);
FORCEPROP 1 LAST PACK_TYPE 0402
J 0
(-6750 4150);
DISPLAY 0.617021 (-6750 4150);
PAINT SKYBLUE (-6750 4150);
FORCEPROP 1 LAST TOLERANCE 1%
J 0
(-6850 4150);
DISPLAY 0.617021 (-6850 4150);
PAINT SKYBLUE (-6850 4150);
FORCEPROP 1 LASTPIN (-6800 4200) $PN 2
J 0
(-6838 4212);
DISPLAY 0.617021 (-6838 4212);
PAINT ORANGE (-6838 4212);
FORCEPROP 1 LAST LOCATION R1L24
J 0
(-6950 4250);
DISPLAY 0.617021 (-6950 4250);
PAINT AQUA (-6950 4250);
FORCEPROP 1 LAST VALUE 10.0
J 2
(-6925 4150);
DISPLAY 0.617021 (-6925 4150);
PAINT SKYBLUE (-6925 4150);
FORCEPROP 1 LASTPIN (-7000 4200) $PN 1
J 0
(-6988 4212);
DISPLAY 0.617021 (-6988 4212);
PAINT ORANGE (-6988 4212);
FORCEPROP 1 LAST WATTAGE 1/16W
J 2
(-7025 4150);
DISPLAY 0.617021 (-7025 4150);
PAINT SKYBLUE (-7025 4150);
FORCEPROP 2 LAST CDS_LIB mstr_discrete
J 0
(-6900 4200);
PAINT ORANGE (-6900 4200);
DISPLAY INVISIBLE (-6900 4200);
FORCEPROP 2 LAST CDS_SEC 1
J 0
(-6950 4400);
PAINT MONO (-6950 4400);
DISPLAY INVISIBLE (-6950 4400);
FORCEPROP 2 LAST $SEC 1
J 0
(-6950 4400);
PAINT MONO (-6950 4400);
DISPLAY INVISIBLE (-6950 4400);
FORCEPROP 2 LAST BOM_COST DEBUG
J 0
(-6950 4350);
DISPLAY 1.021277 (-6950 4350);
PAINT ORANGE (-6950 4350);
DISPLAY INVISIBLE (-6950 4350);
FORCEPROP 1 LAST PATH I68
J 0
(-6950 4350);
DISPLAY 0.978723 (-6950 4350);
PAINT WHITE (-6950 4350);
DISPLAY INVISIBLE (-6950 4350);
FORCEPROP 2 LAST ROOM BMC_DEBUG_HEADER
J 0
(-6950 4300);
DISPLAY 1.021277 (-6950 4300);
PAINT ORANGE (-6950 4300);
DISPLAY INVISIBLE (-6950 4300);
FORCEPROP 2 LAST CDS_LOCATION R1L24
J 0
(-6950 4250);
DISPLAY 0.617021 (-6950 4250);
PAINT AQUA (-6950 4250);
DISPLAY INVISIBLE (-6950 4250);
FORCEPROP 1 LAST MATERIAL CHIP
J 0
(-6900 4050);
DISPLAY 0.978723 (-6900 4050);
PAINT SKYBLUE (-6900 4050);
DISPLAY INVISIBLE (-6900 4050);
FORCEADD OFFPAGE..2
(-6050 4200);
FORCEPROP 2 LAST $XR1 155 
J 0
(-5861 4200);
DISPLAY 0.638298 (-5861 4200);
PAINT MONO (-5861 4200);
FORCEPROP 2 LAST $XR0 247 
J 0
(-5861 4200);
DISPLAY 0.638298 (-5861 4200);
PAINT MONO (-5861 4200);
FORCEPROP 2 LAST PATH I69
J 0
(-5825 4250);
DISPLAY 1.021277 (-5825 4250);
PAINT ORANGE (-5825 4250);
DISPLAY INVISIBLE (-5825 4250);
FORCEPROP 2 LAST CDS_LIB mstr_standard
J 0
(-6050 4200);
PAINT ORANGE (-6050 4200);
DISPLAY INVISIBLE (-6050 4200);
FORCEPROP 1 LAST COMMENT_BODY TRUE
J 0
(-6095 4105);
DISPLAY 0.872340 (-6095 4105);
PAINT GREEN (-6095 4105);
DISPLAY INVISIBLE (-6095 4105);
FORCEPROP 1 LAST OFFPAGE TRUE
J 0
(-5725 4075);
DISPLAY 0.872340 (-5725 4075);
PAINT GREEN (-5725 4075);
DISPLAY INVISIBLE (-5725 4075);
FORCEADD OFFPAGE..2
(-6050 4050);
FORCEPROP 2 LAST $XR1 155 
J 0
(-5861 4050);
DISPLAY 0.638298 (-5861 4050);
PAINT MONO (-5861 4050);
FORCEPROP 2 LAST $XR0 247 
J 0
(-5861 4050);
DISPLAY 0.638298 (-5861 4050);
PAINT MONO (-5861 4050);
FORCEPROP 2 LAST PATH I70
J 0
(-5825 4100);
DISPLAY 1.021277 (-5825 4100);
PAINT ORANGE (-5825 4100);
DISPLAY INVISIBLE (-5825 4100);
FORCEPROP 1 LAST OFFPAGE TRUE
J 0
(-5725 3925);
DISPLAY 0.872340 (-5725 3925);
PAINT GREEN (-5725 3925);
DISPLAY INVISIBLE (-5725 3925);
FORCEPROP 2 LAST CDS_LIB mstr_standard
J 0
(-6050 4050);
PAINT ORANGE (-6050 4050);
DISPLAY INVISIBLE (-6050 4050);
FORCEPROP 1 LAST COMMENT_BODY TRUE
J 0
(-6095 3955);
DISPLAY 0.872340 (-6095 3955);
PAINT GREEN (-6095 3955);
DISPLAY INVISIBLE (-6095 3955);
FORCEADD OFFPAGE..2
(-6050 3900);
FORCEPROP 2 LAST $XR1 155 
J 0
(-5861 3900);
DISPLAY 0.638298 (-5861 3900);
PAINT MONO (-5861 3900);
FORCEPROP 2 LAST $XR0 247 
J 0
(-5861 3900);
DISPLAY 0.638298 (-5861 3900);
PAINT MONO (-5861 3900);
FORCEPROP 1 LAST OFFPAGE TRUE
J 0
(-5725 3775);
DISPLAY 0.872340 (-5725 3775);
PAINT GREEN (-5725 3775);
DISPLAY INVISIBLE (-5725 3775);
FORCEPROP 2 LAST PATH I71
J 0
(-5825 3950);
DISPLAY 1.021277 (-5825 3950);
PAINT ORANGE (-5825 3950);
DISPLAY INVISIBLE (-5825 3950);
FORCEPROP 2 LAST CDS_LIB mstr_standard
J 0
(-6050 3900);
PAINT ORANGE (-6050 3900);
DISPLAY INVISIBLE (-6050 3900);
FORCEPROP 1 LAST COMMENT_BODY TRUE
J 0
(-6095 3805);
DISPLAY 0.872340 (-6095 3805);
PAINT GREEN (-6095 3805);
DISPLAY INVISIBLE (-6095 3805);
FORCEADD OFFPAGE..2
(-6050 3750);
FORCEPROP 2 LAST $XR1 155 
J 0
(-5861 3750);
DISPLAY 0.638298 (-5861 3750);
PAINT MONO (-5861 3750);
FORCEPROP 2 LAST $XR0 247 
J 0
(-5861 3750);
DISPLAY 0.638298 (-5861 3750);
PAINT MONO (-5861 3750);
FORCEPROP 1 LAST OFFPAGE TRUE
J 0
(-5725 3625);
DISPLAY 0.872340 (-5725 3625);
PAINT GREEN (-5725 3625);
DISPLAY INVISIBLE (-5725 3625);
FORCEPROP 2 LAST PATH I72
J 0
(-5825 3800);
DISPLAY 1.021277 (-5825 3800);
PAINT ORANGE (-5825 3800);
DISPLAY INVISIBLE (-5825 3800);
FORCEPROP 2 LAST CDS_LIB mstr_standard
J 0
(-6050 3750);
PAINT ORANGE (-6050 3750);
DISPLAY INVISIBLE (-6050 3750);
FORCEPROP 1 LAST COMMENT_BODY TRUE
J 0
(-6095 3655);
DISPLAY 0.872340 (-6095 3655);
PAINT GREEN (-6095 3655);
DISPLAY INVISIBLE (-6095 3655);
FORCEADD RES..1
(-6900 4050);
FORCEPROP 1 LAST LOCATION R1L20
J 0
(-6950 4100);
DISPLAY 0.617021 (-6950 4100);
PAINT AQUA (-6950 4100);
FORCEPROP 1 LAST PART_NUMBER G21796-066
J 0
(-6800 4075);
DISPLAY 0.617021 (-6800 4075);
PAINT BLUE (-6800 4075);
FORCEPROP 1 LAST PACK_TYPE 0402
J 0
(-6750 4000);
DISPLAY 0.617021 (-6750 4000);
PAINT SKYBLUE (-6750 4000);
FORCEPROP 1 LAST TOLERANCE 1%
J 0
(-6850 4000);
DISPLAY 0.617021 (-6850 4000);
PAINT SKYBLUE (-6850 4000);
FORCEPROP 1 LASTPIN (-6800 4050) $PN 2
J 0
(-6838 4062);
DISPLAY 0.617021 (-6838 4062);
PAINT ORANGE (-6838 4062);
FORCEPROP 1 LAST VALUE 10.0
J 2
(-6925 4000);
DISPLAY 0.617021 (-6925 4000);
PAINT SKYBLUE (-6925 4000);
FORCEPROP 1 LASTPIN (-7000 4050) $PN 1
J 0
(-6988 4062);
DISPLAY 0.617021 (-6988 4062);
PAINT ORANGE (-6988 4062);
FORCEPROP 1 LAST WATTAGE 1/16W
J 2
(-7025 4000);
DISPLAY 0.617021 (-7025 4000);
PAINT SKYBLUE (-7025 4000);
FORCEPROP 2 LAST BOM_COST DEBUG
J 0
(-6950 4200);
DISPLAY 1.021277 (-6950 4200);
PAINT ORANGE (-6950 4200);
DISPLAY INVISIBLE (-6950 4200);
FORCEPROP 2 LAST CDS_SEC 1
J 0
(-6950 4250);
PAINT MONO (-6950 4250);
DISPLAY INVISIBLE (-6950 4250);
FORCEPROP 2 LAST $SEC 1
J 0
(-6950 4250);
PAINT MONO (-6950 4250);
DISPLAY INVISIBLE (-6950 4250);
FORCEPROP 1 LAST PATH I73
J 0
(-6950 4200);
DISPLAY 0.978723 (-6950 4200);
PAINT WHITE (-6950 4200);
DISPLAY INVISIBLE (-6950 4200);
FORCEPROP 2 LAST ROOM BMC_DEBUG_HEADER
J 0
(-6950 4150);
DISPLAY 1.021277 (-6950 4150);
PAINT ORANGE (-6950 4150);
DISPLAY INVISIBLE (-6950 4150);
FORCEPROP 2 LAST CDS_LOCATION R1L20
J 0
(-6950 4100);
DISPLAY 0.617021 (-6950 4100);
PAINT AQUA (-6950 4100);
DISPLAY INVISIBLE (-6950 4100);
FORCEPROP 2 LAST CDS_LIB mstr_discrete
J 0
(-6900 4050);
PAINT ORANGE (-6900 4050);
DISPLAY INVISIBLE (-6900 4050);
FORCEPROP 1 LAST MATERIAL CHIP
J 0
(-6900 3900);
DISPLAY 0.978723 (-6900 3900);
PAINT SKYBLUE (-6900 3900);
DISPLAY INVISIBLE (-6900 3900);
FORCEADD RES..1
(-6900 3900);
FORCEPROP 1 LAST PART_NUMBER G21796-066
J 0
(-6800 3925);
DISPLAY 0.617021 (-6800 3925);
PAINT BLUE (-6800 3925);
FORCEPROP 1 LAST PACK_TYPE 0402
J 0
(-6750 3850);
DISPLAY 0.617021 (-6750 3850);
PAINT SKYBLUE (-6750 3850);
FORCEPROP 1 LASTPIN (-6800 3900) $PN 2
J 0
(-6838 3912);
DISPLAY 0.617021 (-6838 3912);
PAINT ORANGE (-6838 3912);
FORCEPROP 1 LAST TOLERANCE 1%
J 0
(-6850 3850);
DISPLAY 0.617021 (-6850 3850);
PAINT SKYBLUE (-6850 3850);
FORCEPROP 1 LAST LOCATION R1L18
J 0
(-6950 3950);
DISPLAY 0.617021 (-6950 3950);
PAINT AQUA (-6950 3950);
FORCEPROP 1 LAST VALUE 10.0
J 2
(-6925 3850);
DISPLAY 0.617021 (-6925 3850);
PAINT SKYBLUE (-6925 3850);
FORCEPROP 1 LASTPIN (-7000 3900) $PN 1
J 0
(-6988 3912);
DISPLAY 0.617021 (-6988 3912);
PAINT ORANGE (-6988 3912);
FORCEPROP 1 LAST WATTAGE 1/16W
J 2
(-7025 3850);
DISPLAY 0.617021 (-7025 3850);
PAINT SKYBLUE (-7025 3850);
FORCEPROP 2 LAST CDS_SEC 1
J 0
(-6950 4100);
PAINT MONO (-6950 4100);
DISPLAY INVISIBLE (-6950 4100);
FORCEPROP 2 LAST $SEC 1
J 0
(-6950 4100);
PAINT MONO (-6950 4100);
DISPLAY INVISIBLE (-6950 4100);
FORCEPROP 2 LAST CDS_LIB mstr_discrete
J 0
(-6900 3900);
PAINT ORANGE (-6900 3900);
DISPLAY INVISIBLE (-6900 3900);
FORCEPROP 1 LAST MATERIAL CHIP
J 0
(-6900 3750);
DISPLAY 0.978723 (-6900 3750);
PAINT SKYBLUE (-6900 3750);
DISPLAY INVISIBLE (-6900 3750);
FORCEPROP 2 LAST BOM_COST DEBUG
J 0
(-6950 4050);
DISPLAY 1.021277 (-6950 4050);
PAINT ORANGE (-6950 4050);
DISPLAY INVISIBLE (-6950 4050);
FORCEPROP 1 LAST PATH I74
J 0
(-6950 4050);
DISPLAY 0.978723 (-6950 4050);
PAINT WHITE (-6950 4050);
DISPLAY INVISIBLE (-6950 4050);
FORCEPROP 2 LAST ROOM BMC_DEBUG_HEADER
J 0
(-6950 4000);
DISPLAY 1.021277 (-6950 4000);
PAINT ORANGE (-6950 4000);
DISPLAY INVISIBLE (-6950 4000);
FORCEPROP 2 LAST CDS_LOCATION R1L18
J 0
(-6950 3950);
DISPLAY 0.617021 (-6950 3950);
PAINT AQUA (-6950 3950);
DISPLAY INVISIBLE (-6950 3950);
FORCEADD RES..1
(-6900 3750);
FORCEPROP 1 LAST PART_NUMBER G21796-066
J 0
(-6800 3775);
DISPLAY 0.617021 (-6800 3775);
PAINT BLUE (-6800 3775);
FORCEPROP 1 LAST PACK_TYPE 0402
J 0
(-6750 3700);
DISPLAY 0.617021 (-6750 3700);
PAINT SKYBLUE (-6750 3700);
FORCEPROP 1 LAST TOLERANCE 1%
J 0
(-6850 3700);
DISPLAY 0.617021 (-6850 3700);
PAINT SKYBLUE (-6850 3700);
FORCEPROP 1 LASTPIN (-6800 3750) $PN 2
J 0
(-6838 3762);
DISPLAY 0.617021 (-6838 3762);
PAINT ORANGE (-6838 3762);
FORCEPROP 1 LAST LOCATION R1L14
J 0
(-6950 3800);
DISPLAY 0.617021 (-6950 3800);
PAINT AQUA (-6950 3800);
FORCEPROP 1 LAST VALUE 10.0
J 2
(-6925 3700);
DISPLAY 0.617021 (-6925 3700);
PAINT SKYBLUE (-6925 3700);
FORCEPROP 1 LAST WATTAGE 1/16W
J 2
(-7025 3700);
DISPLAY 0.617021 (-7025 3700);
PAINT SKYBLUE (-7025 3700);
FORCEPROP 1 LASTPIN (-7000 3750) $PN 1
J 0
(-6988 3762);
DISPLAY 0.617021 (-6988 3762);
PAINT ORANGE (-6988 3762);
FORCEPROP 2 LAST CDS_LIB mstr_discrete
J 0
(-6900 3750);
PAINT ORANGE (-6900 3750);
DISPLAY INVISIBLE (-6900 3750);
FORCEPROP 1 LAST MATERIAL CHIP
J 0
(-6900 3600);
DISPLAY 0.978723 (-6900 3600);
PAINT SKYBLUE (-6900 3600);
DISPLAY INVISIBLE (-6900 3600);
FORCEPROP 2 LAST BOM_COST DEBUG
J 0
(-6950 3900);
DISPLAY 1.021277 (-6950 3900);
PAINT ORANGE (-6950 3900);
DISPLAY INVISIBLE (-6950 3900);
FORCEPROP 2 LAST CDS_SEC 1
J 0
(-6950 3950);
PAINT MONO (-6950 3950);
DISPLAY INVISIBLE (-6950 3950);
FORCEPROP 2 LAST $SEC 1
J 0
(-6950 3950);
PAINT MONO (-6950 3950);
DISPLAY INVISIBLE (-6950 3950);
FORCEPROP 1 LAST PATH I75
J 0
(-6950 3900);
DISPLAY 0.978723 (-6950 3900);
PAINT WHITE (-6950 3900);
DISPLAY INVISIBLE (-6950 3900);
FORCEPROP 2 LAST ROOM BMC_DEBUG_HEADER
J 0
(-6950 3850);
DISPLAY 1.021277 (-6950 3850);
PAINT ORANGE (-6950 3850);
DISPLAY INVISIBLE (-6950 3850);
FORCEPROP 2 LAST CDS_LOCATION R1L14
J 0
(-6950 3800);
DISPLAY 0.617021 (-6950 3800);
PAINT AQUA (-6950 3800);
DISPLAY INVISIBLE (-6950 3800);
FORCEADD RES..1
(-6900 3600);
FORCEPROP 1 LAST PART_NUMBER G21796-066
J 0
(-6800 3625);
DISPLAY 0.617021 (-6800 3625);
PAINT BLUE (-6800 3625);
FORCEPROP 1 LASTPIN (-6800 3600) $PN 2
J 0
(-6838 3612);
DISPLAY 0.617021 (-6838 3612);
PAINT ORANGE (-6838 3612);
FORCEPROP 1 LAST TOLERANCE 1%
J 0
(-6850 3550);
DISPLAY 0.617021 (-6850 3550);
PAINT SKYBLUE (-6850 3550);
FORCEPROP 1 LAST LOCATION R1L11
J 0
(-6950 3650);
DISPLAY 0.617021 (-6950 3650);
PAINT AQUA (-6950 3650);
FORCEPROP 1 LAST VALUE 10.0
J 2
(-6925 3550);
DISPLAY 0.617021 (-6925 3550);
PAINT SKYBLUE (-6925 3550);
FORCEPROP 1 LASTPIN (-7000 3600) $PN 1
J 0
(-6988 3612);
DISPLAY 0.617021 (-6988 3612);
PAINT ORANGE (-6988 3612);
FORCEPROP 1 LAST WATTAGE 1/16W
J 2
(-7025 3550);
DISPLAY 0.617021 (-7025 3550);
PAINT SKYBLUE (-7025 3550);
FORCEPROP 1 LAST PACK_TYPE 0402
J 0
(-6750 3550);
DISPLAY 0.617021 (-6750 3550);
PAINT SKYBLUE (-6750 3550);
FORCEPROP 2 LAST CDS_LIB mstr_discrete
J 0
(-6900 3600);
PAINT ORANGE (-6900 3600);
DISPLAY INVISIBLE (-6900 3600);
FORCEPROP 1 LAST MATERIAL CHIP
J 0
(-6900 3450);
DISPLAY 0.978723 (-6900 3450);
PAINT SKYBLUE (-6900 3450);
DISPLAY INVISIBLE (-6900 3450);
FORCEPROP 2 LAST ROOM BMC_DEBUG_HEADER
J 0
(-6950 3700);
DISPLAY 1.021277 (-6950 3700);
PAINT ORANGE (-6950 3700);
DISPLAY INVISIBLE (-6950 3700);
FORCEPROP 1 LAST PATH I76
J 0
(-6950 3750);
DISPLAY 0.978723 (-6950 3750);
PAINT WHITE (-6950 3750);
DISPLAY INVISIBLE (-6950 3750);
FORCEPROP 2 LAST CDS_LOCATION R1L11
J 0
(-6950 3650);
DISPLAY 0.617021 (-6950 3650);
PAINT AQUA (-6950 3650);
DISPLAY INVISIBLE (-6950 3650);
FORCEPROP 2 LAST $SEC 1
J 0
(-6950 3800);
PAINT MONO (-6950 3800);
DISPLAY INVISIBLE (-6950 3800);
FORCEPROP 2 LAST CDS_SEC 1
J 0
(-6950 3800);
PAINT MONO (-6950 3800);
DISPLAY INVISIBLE (-6950 3800);
FORCEPROP 2 LAST BOM_COST DEBUG
J 0
(-6950 3750);
DISPLAY 1.021277 (-6950 3750);
PAINT ORANGE (-6950 3750);
DISPLAY INVISIBLE (-6950 3750);
FORCEADD OFFPAGE..1
(-7475 4500);
FORCEPROP 2 LAST $XR1 146 
J 0
(-7847 4500);
DISPLAY 0.638298 (-7847 4500);
PAINT MONO (-7847 4500);
FORCEPROP 2 LAST $XR0 120 
J 0
(-7727 4500);
DISPLAY 0.638298 (-7727 4500);
PAINT MONO (-7727 4500);
FORCEPROP 1 LAST OFFPAGE TRUE
J 0
(-7150 4375);
DISPLAY 0.872340 (-7150 4375);
PAINT GREEN (-7150 4375);
DISPLAY INVISIBLE (-7150 4375);
FORCEPROP 1 LAST COMMENT_BODY TRUE
J 0
(-7350 4400);
DISPLAY 0.872340 (-7350 4400);
PAINT GREEN (-7350 4400);
DISPLAY INVISIBLE (-7350 4400);
FORCEPROP 2 LAST CDS_LIB mstr_standard
J 0
(-7475 4500);
PAINT ORANGE (-7475 4500);
DISPLAY INVISIBLE (-7475 4500);
FORCEPROP 2 LAST PATH I77
J 0
(-7725 4550);
DISPLAY 1.021277 (-7725 4550);
PAINT ORANGE (-7725 4550);
DISPLAY INVISIBLE (-7725 4550);
FORCEADD OFFPAGE..1
(-7475 4650);
FORCEPROP 2 LAST $XR1 146 
J 0
(-7847 4650);
DISPLAY 0.638298 (-7847 4650);
PAINT MONO (-7847 4650);
FORCEPROP 2 LAST $XR0 120 
J 0
(-7727 4650);
DISPLAY 0.638298 (-7727 4650);
PAINT MONO (-7727 4650);
FORCEPROP 1 LAST OFFPAGE TRUE
J 0
(-7150 4525);
DISPLAY 0.872340 (-7150 4525);
PAINT GREEN (-7150 4525);
DISPLAY INVISIBLE (-7150 4525);
FORCEPROP 1 LAST COMMENT_BODY TRUE
J 0
(-7350 4550);
DISPLAY 0.872340 (-7350 4550);
PAINT GREEN (-7350 4550);
DISPLAY INVISIBLE (-7350 4550);
FORCEPROP 2 LAST CDS_LIB mstr_standard
J 0
(-7475 4650);
PAINT ORANGE (-7475 4650);
DISPLAY INVISIBLE (-7475 4650);
FORCEPROP 2 LAST PATH I78
J 0
(-7725 4700);
DISPLAY 1.021277 (-7725 4700);
PAINT ORANGE (-7725 4700);
DISPLAY INVISIBLE (-7725 4700);
FORCEADD OFFPAGE..1
(-7475 4350);
FORCEPROP 2 LAST $XR1 146 
J 0
(-7847 4350);
DISPLAY 0.638298 (-7847 4350);
PAINT MONO (-7847 4350);
FORCEPROP 2 LAST $XR0 120 
J 0
(-7727 4350);
DISPLAY 0.638298 (-7727 4350);
PAINT MONO (-7727 4350);
FORCEPROP 1 LAST OFFPAGE TRUE
J 0
(-7150 4225);
DISPLAY 0.872340 (-7150 4225);
PAINT GREEN (-7150 4225);
DISPLAY INVISIBLE (-7150 4225);
FORCEPROP 1 LAST COMMENT_BODY TRUE
J 0
(-7350 4250);
DISPLAY 0.872340 (-7350 4250);
PAINT GREEN (-7350 4250);
DISPLAY INVISIBLE (-7350 4250);
FORCEPROP 2 LAST CDS_LIB mstr_standard
J 0
(-7475 4350);
PAINT ORANGE (-7475 4350);
DISPLAY INVISIBLE (-7475 4350);
FORCEPROP 2 LAST PATH I79
J 0
(-7725 4400);
DISPLAY 1.021277 (-7725 4400);
PAINT ORANGE (-7725 4400);
DISPLAY INVISIBLE (-7725 4400);
FORCEADD RES..2
(-1900 1725);
FORCEPROP 2 LAST ROOM BMC_DEBUG_HEADER
J 0
(-1850 1900);
DISPLAY 1.021277 (-1850 1900);
PAINT ORANGE (-1850 1900);
DISPLAY INVISIBLE (-1850 1900);
FORCEPROP 1 LAST PATH I80
J 0
(-1850 1900);
DISPLAY 0.978723 (-1850 1900);
PAINT WHITE (-1850 1900);
DISPLAY INVISIBLE (-1850 1900);
FORCEPROP 2 LAST CDS_LOCATION R9A7
J 0
(-1855 1850);
DISPLAY 0.617021 (-1855 1850);
PAINT AQUA (-1855 1850);
DISPLAY INVISIBLE (-1855 1850);
FORCEPROP 2 LAST SEC 1
J 0
(-1850 1950);
DISPLAY 0.680851 (-1850 1950);
PAINT MONO (-1850 1950);
DISPLAY INVISIBLE (-1850 1950);
FORCEPROP 2 LAST BOM_COST DEBUG
J 0
(-1850 1950);
DISPLAY 1.021277 (-1850 1950);
PAINT ORANGE (-1850 1950);
DISPLAY INVISIBLE (-1850 1950);
FORCEPROP 2 LAST SEC_TYPE 0402
J 0
(-1850 1950);
DISPLAY 1.021277 (-1850 1950);
PAINT ORANGE (-1850 1950);
DISPLAY INVISIBLE (-1850 1950);
FORCEPROP 2 LAST CDS_LIB mstr_discrete
J 0
(-1900 1725);
PAINT ORANGE (-1900 1725);
DISPLAY INVISIBLE (-1900 1725);
FORCEPROP 1 LAST WATTAGE 1/16W
J 0
(-1860 1700);
DISPLAY 0.617021 (-1860 1700);
PAINT SKYBLUE (-1860 1700);
FORCEPROP 1 LASTPIN (-1900 1825) $PN 1
J 0
(-1895 1787);
DISPLAY 0.617021 (-1895 1787);
PAINT ORANGE (-1895 1787);
FORCEPROP 1 LAST PART_NUMBER G21796-112
J 0
(-1860 1600);
DISPLAY 0.617021 (-1860 1600);
PAINT BLUE (-1860 1600);
FORCEPROP 1 LASTPIN (-1900 1625) $PN 2
J 0
(-1895 1635);
DISPLAY 0.617021 (-1895 1635);
PAINT ORANGE (-1895 1635);
FORCEPROP 1 LAST TOLERANCE 1%
J 0
(-1855 1750);
DISPLAY 0.617021 (-1855 1750);
PAINT SKYBLUE (-1855 1750);
FORCEPROP 1 LAST MATERIAL CHIP
J 0
(-1860 1650);
DISPLAY 0.617021 (-1860 1650);
PAINT SKYBLUE (-1860 1650);
FORCEPROP 1 LAST LOCATION R9A7
J 0
(-1855 1850);
DISPLAY 0.617021 (-1855 1850);
PAINT AQUA (-1855 1850);
FORCEPROP 1 LAST VALUE 2.21K
J 0
(-1855 1800);
DISPLAY 0.617021 (-1855 1800);
PAINT SKYBLUE (-1855 1800);
FORCEPROP 1 LAST PACK_TYPE 0402
J 0
(-1860 1550);
DISPLAY 0.617021 (-1860 1550);
PAINT SKYBLUE (-1860 1550);
FORCEADD P3V3_STBY..1
(-1900 1975);
FORCEPROP 3 LASTPIN (-1900 1925) SIG_NAME P3V3_STBY\g
J 0
(-1890 1935);
DISPLAY 0.659574 (-1890 1935);
PAINT MONO (-1890 1935);
DISPLAY INVISIBLE (-1890 1935);
FORCEPROP 1 LAST PATH I81
J 0
(-1855 1977);
DISPLAY 0.340426 (-1855 1977);
PAINT GREEN (-1855 1977);
DISPLAY INVISIBLE (-1855 1977);
FORCEPROP 1 LAST SIZE 1B
J 0
(-1855 1997);
DISPLAY 0.340426 (-1855 1997);
PAINT GREEN (-1855 1997);
DISPLAY INVISIBLE (-1855 1997);
FORCEPROP 1 LAST BODY_TYPE PLUMBING
J 0
(-1945 1932);
DISPLAY 0.340426 (-1945 1932);
PAINT GREEN (-1945 1932);
DISPLAY INVISIBLE (-1945 1932);
FORCEPROP 2 LAST CDS_LIB mstr_symbols
J 0
(-1900 1975);
PAINT ORANGE (-1900 1975);
DISPLAY INVISIBLE (-1900 1975);
FORCEPROP 1 LAST VOLTAGE 3.3V
J 0
(-1945 1932);
DISPLAY 0.340426 (-1945 1932);
PAINT SKYBLUE (-1945 1932);
DISPLAY INVISIBLE (-1945 1932);
FORCEPROP 1 LAST HDL_POWER P3V3_STBY
J 0
(-2200 1850);
DISPLAY 0.872340 (-2200 1850);
PAINT ORANGE (-2200 1850);
DISPLAY INVISIBLE (-2200 1850);
FORCEADD DNS..2
(-2945 1720);
PAINT RED (-2945 1720);
FORCEPROP 1 LAST COMMENT_BODY TRUE
R 1
J 0
(-2870 1495);
DISPLAY 0.872340 (-2870 1495);
PAINT GREEN (-2870 1495);
DISPLAY INVISIBLE (-2870 1495);
FORCEPROP 2 LAST CDS_LIB mstr_misc
J 0
(-2945 1720);
PAINT ORANGE (-2945 1720);
DISPLAY INVISIBLE (-2945 1720);
FORCEADD CAD_NOTE..1
(-1950 3175);
FORCEPROP 1 LAST COMMENT_BODY TRUE
J 0
(-1925 3275);
DISPLAY 0.978723 (-1925 3275);
PAINT ORANGE (-1925 3275);
DISPLAY INVISIBLE (-1925 3275);
FORCEPROP 2 LAST CDS_LIB mstr_symbols
J 0
(-1950 3175);
PAINT ORANGE (-1950 3175);
DISPLAY INVISIBLE (-1950 3175);
FORCEPROP 0 LAST L1 PLACE 0.1UF CAP NEXT TO VCC PIN
J 2
(-1700 3050);
DISPLAY 1.021277 (-1700 3050);
PAINT ORANGE (-1700 3050);
FORCEPROP 0 LAST L2 ON TTL1G07_A
J 2
(-1700 2975);
DISPLAY 1.021277 (-1700 2975);
PAINT ORANGE (-1700 2975);
FORCEADD INTEL_CORP_BPAGE..1
(0 0);
FORCEPROP 1 LAST CDS_CON_LAST_MODIFIED Tue Dec 01 14:59:04 2015
J 0
(-1425 325);
DISPLAY 1.361702 (-1425 325);
PAINT GREEN (-1425 325);
DISPLAY INVISIBLE (-1425 325);
FORCEPROP 1 LAST CUSTOM_TXT_CDS <CON_LAST_MODIFIED>
J 0
(-1925 350);
PAINT ORANGE (-1925 350);
FORCEPROP 1 LAST CUSTOM_TXT_CDS <CURRENT_DESIGN_SHEET> OF <TOTAL_DESIGN_SHEETS>
J 0
(-500 25);
PAINT ORANGE (-500 25);
FORCEPROP 2 LAST CUSTOM_TXT_CDS <XR_PAGE_TITLE>
J 0
(-7890 5250);
DISPLAY 0.638298 (-7890 5250);
PAINT PINK (-7890 5250);
DISPLAY INVISIBLE (-7890 5250);
FORCEPROP 1 LAST SCH_REV 2.420
J 0
(-250 150);
DISPLAY 0.978723 (-250 150);
PAINT YELLOW (-250 150);
FORCEPROP 1 LAST SCH_DEPT BESD
J 1
(-4450 100);
DISPLAY 1.212766 (-4450 100);
PAINT YELLOW (-4450 100);
FORCEPROP 1 LAST SCH_ADDRESS2 P.O. BOX 58119
J 0
(-3975 75);
DISPLAY 0.617021 (-3975 75);
PAINT GREEN (-3975 75);
FORCEPROP 1 LAST SCH_ADDRESS1 2200 Mission College Blvd.
J 0
(-3975 125);
DISPLAY 0.617021 (-3975 125);
PAINT GREEN (-3975 125);
FORCEPROP 1 LAST SCH_ADDRESS3 Santa Clara, CA 95052-8119
J 0
(-3975 25);
DISPLAY 0.617021 (-3975 25);
PAINT GREEN (-3975 25);
FORCEPROP 1 LAST SCH_NUMBER H4694802
J 0
(-1300 150);
DISPLAY 1.212766 (-1300 150);
PAINT YELLOW (-1300 150);
FORCEPROP 1 LAST SCH_TITLE BMC DEBUG HEADER
J 0
(-7950 50);
DISPLAY 1.212766 (-7950 50);
PAINT ORANGE (-7950 50);
FORCEPROP 1 LAST COMMENT_BODY TRUE
J 0
(12 12);
DISPLAY 0.617021 (12 12);
PAINT GREEN (12 12);
DISPLAY INVISIBLE (12 12);
FORCEPROP 2 LAST CDS_LIB mstr_symbols
J 0
(0 0);
DISPLAY 1.361702 (0 0);
PAINT ORANGE (0 0);
DISPLAY INVISIBLE (0 0);
FORCEPROP 2 LAST PAGE_BORDER TRUE
J 0
(-7890 5250);
DISPLAY 0.851064 (-7890 5250);
PAINT PINK (-7890 5250);
DISPLAY INVISIBLE (-7890 5250);
FORCEPROP 2 LAST CDS_XR_PAGE_TITLE CR-155 : @BASEBOARD_FAB2_LIB.BASEBOARD_FAB2(SCH_1):PAGE155
J 0
(-7890 5250);
DISPLAY 0.638298 (-7890 5250);
PAINT PINK (-7890 5250);
DISPLAY INVISIBLE (-7890 5250);
WIRE 16 -1 (-1900 1925)(-1900 1825);
WIRE 16 -1 (-4825 1175)(-4825 1300);
WIRE 16 -1 (-4825 1300)(-4750 1300);
WIRE 16 -1 (-4950 2850)(-4950 2900);
WIRE 16 -1 (-5500 2850)(-4950 2850);
WIRE 16 -1 (-5500 3000)(-5500 2850);
WIRE 16 -1 (-5350 3000)(-5500 3000);
WIRE 16 -1 (-3325 1825)(-3325 1925);
WIRE 16 -1 (-6050 2850)(-6050 2675);
WIRE 16 -1 (-2950 1925)(-2950 1825);
WIRE 16 -1 (-1550 2775)(-1550 2925);
WIRE 16 -1 (-1550 3275)(-1550 3125);
WIRE 16 -1 (-6050 1650)(-6050 1900);
WIRE 16 -1 (-4100 950)(-4100 875);
WIRE 16 -1 (-5500 3100)(-5500 3250);
WIRE 16 -1 (-5350 3100)(-5500 3100);
WIRE 3 2175 (-5750 3400)(-5750 2800);
WIRE 3 2175 (-5750 2800)(-4700 2800);
WIRE 3 2175 (-5750 3400)(-4700 3400);
WIRE 3 2175 (-4700 3400)(-4700 2800);
WIRE 16 -1 (-5650 2625)(-5150 2625);
FORCEPROP 2 LAST SIG_NAME UART_PWR_SEL
J 0
(-5585 2635);
DISPLAY 0.638298 (-5585 2635);
PAINT ORANGE (-5585 2635);
WIRE 16 -1 (-5650 2625)(-5650 3050);
WIRE 16 -1 (-5350 3050)(-5650 3050);
WIRE 16 -1 (-6050 2350)(-6050 2300);
WIRE 16 -1 (-6050 2475)(-6050 2350);
WIRE 16 -1 (-4850 2350)(-4850 2425);
WIRE 16 -1 (-4850 2350)(-6050 2350);
FORCEPROP 2 LAST SIG_NAME FM_CPLD_DBG_PWR_EN
J 0
(-5585 2360);
DISPLAY 0.617021 (-5585 2360);
PAINT ORANGE (-5585 2360);
FORCEPROP 2 LASTPROP $XRERR UNIQUE?
J 0
(-5825 2360);
DISPLAY 0.638298 (-5825 2360);
PAINT MONO (-5825 2360);
DISPLAY INVISIBLE (-5825 2360);
WIRE 3 2175 (-5700 775)(-500 775);
WIRE 3 2175 (-500 2200)(-500 775);
WIRE 3 2175 (-5700 2200)(-5700 775);
WIRE 3 2175 (-5700 2200)(-500 2200);
WIRE 16 -1 (-4100 2625)(-4125 2625);
WIRE 16 -1 (-4100 1150)(-4100 1300);
WIRE 16 -1 (-4100 1300)(-4150 1300);
WIRE 16 -1 (-4100 1300)(-4100 2625);
FORCEPROP 0 LAST VOLTAGE 5
J 0
(-4100 1850);
DISPLAY 1.021277 (-4100 1850);
PAINT SKYBLUE (-4100 1850);
DISPLAY INVISIBLE (-4100 1850);
FORCEPROP 2 LAST SIG_NAME P5V_STBY_DGB_FS
R 1
J 0
(-4110 1785);
DISPLAY 0.617021 (-4110 1785);
PAINT ORANGE (-4110 1785);
FORCEPROP 2 LASTPROP $XRERR UNIQUE?
J 0
(-4350 1785);
DISPLAY 0.638298 (-4350 1785);
PAINT MONO (-4350 1785);
DISPLAY INVISIBLE (-4350 1785);
WIRE 16 -1 (-7425 3600)(-7000 3600);
FORCEPROP 2 LAST SIG_NAME LED_POSTCODE_7
J 0
(-7425 3610);
DISPLAY 0.617021 (-7425 3610);
PAINT ORANGE (-7425 3610);
WIRE 16 -1 (-7425 3750)(-7000 3750);
FORCEPROP 2 LAST SIG_NAME LED_POSTCODE_6
J 0
(-7425 3760);
DISPLAY 0.617021 (-7425 3760);
PAINT ORANGE (-7425 3760);
WIRE 16 -1 (-7425 3900)(-7000 3900);
FORCEPROP 2 LAST SIG_NAME LED_POSTCODE_5
J 0
(-7425 3910);
DISPLAY 0.617021 (-7425 3910);
PAINT ORANGE (-7425 3910);
WIRE 16 -1 (-7425 4050)(-7000 4050);
FORCEPROP 2 LAST SIG_NAME LED_POSTCODE_4
J 0
(-7425 4060);
DISPLAY 0.617021 (-7425 4060);
PAINT ORANGE (-7425 4060);
WIRE 16 -1 (-7425 4350)(-7000 4350);
FORCEPROP 2 LAST SIG_NAME LED_POSTCODE_2
J 0
(-7425 4360);
DISPLAY 0.617021 (-7425 4360);
PAINT ORANGE (-7425 4360);
WIRE 16 -1 (-7425 4200)(-7000 4200);
FORCEPROP 2 LAST SIG_NAME LED_POSTCODE_3
J 0
(-7425 4210);
DISPLAY 0.617021 (-7425 4210);
PAINT ORANGE (-7425 4210);
WIRE 16 -1 (-7425 4500)(-7000 4500);
FORCEPROP 2 LAST SIG_NAME LED_POSTCODE_1
J 0
(-7425 4510);
DISPLAY 0.617021 (-7425 4510);
PAINT ORANGE (-7425 4510);
WIRE 16 -1 (-7425 4650)(-7000 4650);
FORCEPROP 2 LAST SIG_NAME LED_POSTCODE_0
J 0
(-7425 4660);
DISPLAY 0.617021 (-7425 4660);
PAINT ORANGE (-7425 4660);
WIRE 16 -1 (-6800 3600)(-6100 3600);
FORCEPROP 2 LAST SIG_NAME LED_POSTCODE_7_R
J 0
(-6450 3610);
DISPLAY 0.617021 (-6450 3610);
PAINT ORANGE (-6450 3610);
WIRE 16 -1 (-6800 4050)(-6100 4050);
FORCEPROP 2 LAST SIG_NAME LED_POSTCODE_4_R
J 0
(-6450 4060);
DISPLAY 0.617021 (-6450 4060);
PAINT ORANGE (-6450 4060);
WIRE 16 -1 (-6800 3900)(-6100 3900);
FORCEPROP 2 LAST SIG_NAME LED_POSTCODE_5_R
J 0
(-6450 3910);
DISPLAY 0.617021 (-6450 3910);
PAINT ORANGE (-6450 3910);
WIRE 16 -1 (-6800 4500)(-6100 4500);
FORCEPROP 2 LAST SIG_NAME LED_POSTCODE_1_R
J 0
(-6450 4510);
DISPLAY 0.617021 (-6450 4510);
PAINT ORANGE (-6450 4510);
WIRE 16 -1 (-6800 4350)(-6100 4350);
FORCEPROP 2 LAST SIG_NAME LED_POSTCODE_2_R
J 0
(-6450 4360);
DISPLAY 0.617021 (-6450 4360);
PAINT ORANGE (-6450 4360);
WIRE 16 -1 (-6800 4200)(-6100 4200);
FORCEPROP 2 LAST SIG_NAME LED_POSTCODE_3_R
J 0
(-6450 4210);
DISPLAY 0.617021 (-6450 4210);
PAINT ORANGE (-6450 4210);
WIRE 16 -1 (-6800 4650)(-6100 4650);
FORCEPROP 2 LAST SIG_NAME LED_POSTCODE_0_R
J 0
(-6450 4660);
DISPLAY 0.617021 (-6450 4660);
PAINT ORANGE (-6450 4660);
WIRE 16 -1 (-7650 2000)(-7150 2000);
FORCEPROP 2 LAST SIG_NAME FM_CPLD_DBG_PWR_EN_N
J 0
(-7660 2010);
DISPLAY 0.617021 (-7660 2010);
PAINT ORANGE (-7660 2010);
WIRE 16 -1 (-6250 2000)(-6950 2000);
FORCEPROP 2 LAST SIG_NAME FM_CPLD_DBG_PWR_EN_R_N
J 0
(-6785 2010);
DISPLAY 0.617021 (-6785 2010);
PAINT ORANGE (-6785 2010);
FORCEPROP 2 LASTPROP $XRERR UNIQUE?
J 0
(-7025 2010);
DISPLAY 0.638298 (-7025 2010);
PAINT MONO (-7025 2010);
DISPLAY INVISIBLE (-7025 2010);
WIRE 16 -1 (-5425 1350)(-4750 1350);
FORCEPROP 2 LAST SIG_NAME FM_DEBUG_RST_BTN_N
J 0
(-5450 1360);
DISPLAY 0.617021 (-5450 1360);
PAINT ORANGE (-5450 1360);
WIRE 16 -1 (-5400 1400)(-4750 1400);
FORCEPROP 2 LAST SIG_NAME SPA_MID_DBG_TX
J 0
(-5410 1410);
DISPLAY 0.680851 (-5410 1410);
PAINT ORANGE (-5410 1410);
WIRE 16 -1 (-5400 1450)(-4750 1450);
FORCEPROP 2 LAST SIG_NAME LED_POSTCODE_6_R
J 0
(-5425 1460);
DISPLAY 0.617021 (-5425 1460);
PAINT ORANGE (-5425 1460);
WIRE 16 -1 (-5400 1500)(-4750 1500);
FORCEPROP 2 LAST SIG_NAME LED_POSTCODE_4_R
J 0
(-5425 1510);
DISPLAY 0.617021 (-5425 1510);
PAINT ORANGE (-5425 1510);
WIRE 16 -1 (-5400 1550)(-4750 1550);
FORCEPROP 2 LAST SIG_NAME LED_POSTCODE_2_R
J 0
(-5425 1560);
DISPLAY 0.617021 (-5425 1560);
PAINT ORANGE (-5425 1560);
WIRE 16 -1 (-5400 1600)(-4750 1600);
FORCEPROP 2 LAST SIG_NAME LED_POSTCODE_0_R
J 0
(-5425 1610);
DISPLAY 0.617021 (-5425 1610);
PAINT ORANGE (-5425 1610);
WIRE 16 -1 (-4150 1450)(-3725 1450);
FORCEPROP 2 LAST SIG_NAME LED_POSTCODE_7_R
J 2
(-3725 1460);
DISPLAY 0.617021 (-3725 1460);
PAINT ORANGE (-3725 1460);
WIRE 16 -1 (-4150 1500)(-3725 1500);
FORCEPROP 2 LAST SIG_NAME LED_POSTCODE_5_R
J 2
(-3725 1510);
DISPLAY 0.617021 (-3725 1510);
PAINT ORANGE (-3725 1510);
WIRE 16 -1 (-4150 1550)(-3725 1550);
FORCEPROP 2 LAST SIG_NAME LED_POSTCODE_3_R
J 2
(-3725 1560);
DISPLAY 0.617021 (-3725 1560);
PAINT ORANGE (-3725 1560);
WIRE 16 -1 (-4150 1600)(-3725 1600);
FORCEPROP 2 LAST SIG_NAME LED_POSTCODE_1_R
J 2
(-3725 1610);
DISPLAY 0.617021 (-3725 1610);
PAINT ORANGE (-3725 1610);
WIRE 16 -1 (-1475 1400)(-950 1400);
FORCEPROP 2 LAST SIG_NAME SPA_MID_DBG1__RX
J 0
(-1360 1410);
DISPLAY 0.617021 (-1360 1410);
PAINT ORANGE (-1360 1410);
WIRE 16 -1 (-4150 1350)(-3325 1350);
FORCEPROP 2 LAST SIG_NAME FM_UART_SWITCH_N
J 0
(-4035 1360);
DISPLAY 0.617021 (-4035 1360);
PAINT ORANGE (-4035 1360);
WIRE 16 -1 (-3325 1625)(-3325 1350);
WIRE 16 -1 (-3325 950)(-3325 1350);
WIRE 16 -1 (-3325 950)(-1750 950);
WIRE 16 -1 (-4150 1400)(-2950 1400);
FORCEPROP 2 LAST SIG_NAME SPA_5V_SIN_SW
J 0
(-4035 1400);
DISPLAY 0.617021 (-4035 1400);
PAINT ORANGE (-4035 1400);
FORCEPROP 2 LASTPROP $XRERR UNIQUE?
J 0
(-4275 1400);
DISPLAY 0.638298 (-4275 1400);
PAINT MONO (-4275 1400);
DISPLAY INVISIBLE (-4275 1400);
WIRE 16 -1 (-2950 1625)(-2950 1400);
WIRE 16 -1 (-2725 1775)(-2500 1775);
WIRE 16 -1 (-2950 1400)(-2725 1400);
WIRE 16 -1 (-2725 1400)(-2650 1400);
WIRE 16 -1 (-2725 1400)(-2725 1775);
WIRE 16 -1 (-6800 3750)(-6100 3750);
FORCEPROP 2 LAST SIG_NAME LED_POSTCODE_6_R
J 0
(-6450 3760);
DISPLAY 0.617021 (-6450 3760);
PAINT ORANGE (-6450 3760);
WIRE 16 -1 (-2300 1775)(-1975 1775);
WIRE 16 -1 (-2400 1400)(-1975 1400);
FORCEPROP 2 LAST SIG_NAME SPA_SIN_SW_R
J 0
(-2260 1410);
DISPLAY 0.617021 (-2260 1410);
PAINT ORANGE (-2260 1410);
FORCEPROP 2 LASTPROP $XRERR UNIQUE?
J 0
(-2500 1410);
DISPLAY 0.638298 (-2500 1410);
PAINT MONO (-2500 1410);
DISPLAY INVISIBLE (-2500 1410);
WIRE 16 -1 (-1975 1775)(-1975 1400);
WIRE 16 -1 (-1900 1625)(-1900 1400);
WIRE 16 -1 (-1975 1400)(-1900 1400);
WIRE 16 -1 (-1675 1400)(-1900 1400);
WIRE 16 -1 (-4750 2625)(-4425 2625);
FORCEPROP 0 LAST VOLTAGE 5
J 0
(-4775 2650);
DISPLAY 1.021277 (-4775 2650);
PAINT SKYBLUE (-4775 2650);
DISPLAY INVISIBLE (-4775 2650);
FORCEPROP 2 LAST SIG_NAME P5V_STBY_DBG
J 0
(-4785 2585);
DISPLAY 0.617021 (-4785 2585);
PAINT ORANGE (-4785 2585);
FORCEPROP 2 LASTPROP $XRERR UNIQUE?
J 0
(-5025 2585);
DISPLAY 0.638298 (-5025 2585);
PAINT MONO (-5025 2585);
DISPLAY INVISIBLE (-5025 2585);
DOT 1 (-1900 1400);
DOT 1 (-3325 1350);
DOT 1 (-6050 2350);
DOT 1 (-4100 1300);
DOT 1 (-2950 1400);
DOT 1 (-2725 1400);
DOT 1 (-1975 1400);
FORCENOTE
TP ADD A JUMPER J1W1
(-5750 3400) 0;
DISPLAY LEFT (-5750 3400);
DISPLAY 1.021277 (-5750 3400);
PAINT RED (-5750 3400);
FORCENOTE
1-2 (DEFAULT)
(-5150 3100) 0;
DISPLAY LEFT (-5150 3100);
DISPLAY 1.021277 (-5150 3100);
PAINT PURPLE (-5150 3100);
FORCENOTE
TP FAB1 CHANGE R9A5 FRO 20K TO 15K
(-4050 2125) 0;
DISPLAY LEFT (-4050 2125);
DISPLAY 1.021277 (-4050 2125);
PAINT RED (-4050 2125);
FORCENOTE
CHANGE NET NAME FOR RX AND  GATE1123
(-1775 1900) 0;
DISPLAY LEFT (-1775 1900);
DISPLAY 1.021277 (-1775 1900);
PAINT RED (-1775 1900);
FORCENOTE
TP FAB1 RESERVE R6W19 1119
(-2550 2100) 0;
DISPLAY LEFT (-2550 2100);
DISPLAY 1.021277 (-2550 2100);
PAINT RED (-2550 2100);
FORCENOTE
1119
(-4025 2050) 0;
DISPLAY LEFT (-4025 2050);
DISPLAY 1.021277 (-4025 2050);
PAINT PURPLE (-4025 2050);
FORCENOTE
ROOM=MIO_VIDEO
(-7909 165) 0;
DISPLAY LEFT (-7909 165);
DISPLAY 0.617021 (-7909 165);
PAINT PURPLE (-7909 165);
FORCENOTE
$CDS_IMAGE|dbg_pwr_en_truth_table_edited_20150327.JPG|3263|763
(-3625 4325) 0;
DISPLAY LEFT (-3625 4325);
QUIT
